FILE_TYPE = MACRO_DRAWING;
SET COLOR_WIRE YELLOW;
SET COLOR_PROP ORANGE;
SET COLOR_DOT WHITE;
SET COLOR_ARC YELLOW;
SET COLOR_BODY GREEN;
SET COLOR_NOTE PURPLE;
SET PROP_DISPLAY VALUE;
SET PAGE_NUMBER P84;
FORCEADD UNIVERSAL_POWER..1
R 2
(-1775 2475);
FORCEPROP 3 LASTPIN (-1775 2425) SIG_NAME P3V3_STBY\g
J 0
(-1765 2435);
DISPLAY 0.659574 (-1765 2435);
PAINT MONO (-1765 2435);
DISPLAY INVISIBLE (-1765 2435);
FORCEPROP 1 LAST HDL_POWER P3V3_STBY
J 1
(-1775 2525);
DISPLAY 0.489362 (-1775 2525);
PAINT GREEN (-1775 2525);
FORCEPROP 1 LAST PATH I1
J 2
(-1825 2500);
DISPLAY 0.872340 (-1825 2500);
PAINT AQUA (-1825 2500);
DISPLAY INVISIBLE (-1825 2500);
FORCEPROP 2 LAST CDS_LIB pure_quanta_power
J 0
(-1775 2475);
DISPLAY INVISIBLE (-1775 2475);
FORCEADD OFFPAGE..2
R 2
(-3525 1875);
FORCEPROP 2 LAST $XR1 79 
J 0
(-3870 1875);
DISPLAY 0.638298 (-3870 1875);
PAINT MONO (-3870 1875);
FORCEPROP 2 LAST $XR0 148 
J 0
(-3780 1875);
DISPLAY 0.638298 (-3780 1875);
PAINT MONO (-3780 1875);
FORCEPROP 2 LAST PATH I10
J 0
(-3775 1925);
DISPLAY 0.680851 (-3775 1925);
DISPLAY INVISIBLE (-3775 1925);
FORCEPROP 1 LAST COMMENT_BODY TRUE
J 2
(-3480 1780);
DISPLAY 0.872340 (-3480 1780);
PAINT GREEN (-3480 1780);
DISPLAY INVISIBLE (-3480 1780);
FORCEPROP 1 LAST OFFPAGE TRUE
J 2
(-3850 1750);
DISPLAY 0.872340 (-3850 1750);
PAINT GREEN (-3850 1750);
DISPLAY INVISIBLE (-3850 1750);
FORCEPROP 2 LAST CDS_LIB standard
J 0
(-3525 1875);
DISPLAY INVISIBLE (-3525 1875);
FORCEADD OFFPAGE..1
(-3525 1925);
FORCEPROP 2 LAST $XR1 148 
J 0
(-3896 1925);
DISPLAY 0.638298 (-3896 1925);
PAINT MONO (-3896 1925);
FORCEPROP 2 LAST $XR0 79 
J 0
(-3776 1925);
DISPLAY 0.638298 (-3776 1925);
PAINT MONO (-3776 1925);
FORCEPROP 2 LAST PATH I11
J 0
(-3725 1975);
DISPLAY 0.680851 (-3725 1975);
DISPLAY INVISIBLE (-3725 1975);
FORCEPROP 1 LAST COMMENT_BODY TRUE
J 0
(-3400 1825);
DISPLAY 0.872340 (-3400 1825);
PAINT GREEN (-3400 1825);
DISPLAY INVISIBLE (-3400 1825);
FORCEPROP 1 LAST OFFPAGE TRUE
J 0
(-3200 1800);
DISPLAY 0.872340 (-3200 1800);
PAINT GREEN (-3200 1800);
DISPLAY INVISIBLE (-3200 1800);
FORCEPROP 2 LAST CDS_LIB standard
J 0
(-3525 1925);
DISPLAY INVISIBLE (-3525 1925);
FORCEADD OFFPAGE..2
R 2
(-3550 1725);
FORCEPROP 2 LAST $XR1 79 
J 0
(-3895 1725);
DISPLAY 0.638298 (-3895 1725);
PAINT MONO (-3895 1725);
FORCEPROP 2 LAST $XR0 148 
J 0
(-3805 1725);
DISPLAY 0.638298 (-3805 1725);
PAINT MONO (-3805 1725);
FORCEPROP 2 LAST PATH I12
J 0
(-3800 1775);
DISPLAY 0.680851 (-3800 1775);
DISPLAY INVISIBLE (-3800 1775);
FORCEPROP 1 LAST COMMENT_BODY TRUE
J 2
(-3505 1630);
DISPLAY 0.872340 (-3505 1630);
PAINT GREEN (-3505 1630);
DISPLAY INVISIBLE (-3505 1630);
FORCEPROP 1 LAST OFFPAGE TRUE
J 2
(-3875 1600);
DISPLAY 0.872340 (-3875 1600);
PAINT GREEN (-3875 1600);
DISPLAY INVISIBLE (-3875 1600);
FORCEPROP 2 LAST CDS_LIB standard
J 0
(-3550 1725);
DISPLAY INVISIBLE (-3550 1725);
FORCEADD OFFPAGE..2
R 2
(-3550 1625);
FORCEPROP 2 LAST $XR1 79 
J 0
(-3895 1625);
DISPLAY 0.638298 (-3895 1625);
PAINT MONO (-3895 1625);
FORCEPROP 2 LAST $XR0 148 
J 0
(-3805 1625);
DISPLAY 0.638298 (-3805 1625);
PAINT MONO (-3805 1625);
FORCEPROP 2 LAST PATH I13
J 0
(-3800 1675);
DISPLAY 0.680851 (-3800 1675);
DISPLAY INVISIBLE (-3800 1675);
FORCEPROP 1 LAST COMMENT_BODY TRUE
J 2
(-3505 1530);
DISPLAY 0.872340 (-3505 1530);
PAINT GREEN (-3505 1530);
DISPLAY INVISIBLE (-3505 1530);
FORCEPROP 1 LAST OFFPAGE TRUE
J 2
(-3875 1500);
DISPLAY 0.872340 (-3875 1500);
PAINT GREEN (-3875 1500);
DISPLAY INVISIBLE (-3875 1500);
FORCEPROP 2 LAST CDS_LIB standard
J 0
(-3550 1625);
DISPLAY INVISIBLE (-3550 1625);
FORCEADD UNIVERSAL_GND..1
(-1900 2025);
FORCEPROP 3 LASTPIN (-1900 2075) SIG_NAME GND\g
J 0
(-1890 2085);
DISPLAY 0.659574 (-1890 2085);
PAINT MONO (-1890 2085);
DISPLAY INVISIBLE (-1890 2085);
FORCEPROP 1 LAST HDL_POWER GND
J 1
(-1875 1950);
DISPLAY 0.872340 (-1875 1950);
PAINT GREEN (-1875 1950);
DISPLAY INVISIBLE (-1875 1950);
FORCEPROP 1 LAST PATH I2
J 0
(-1825 2025);
DISPLAY 0.872340 (-1825 2025);
PAINT AQUA (-1825 2025);
DISPLAY INVISIBLE (-1825 2025);
FORCEPROP 2 LAST CDS_LIB pure_quanta_power
J 0
(-1900 2025);
DISPLAY INVISIBLE (-1900 2025);
FORCEADD OFFPAGE..3
(-5900 5175);
FORCEPROP 2 LAST $XR1 80 
J 0
(-5596 5175);
DISPLAY 0.638298 (-5596 5175);
PAINT MONO (-5596 5175);
FORCEPROP 2 LAST $XR0 55 
J 0
(-5686 5175);
DISPLAY 0.638298 (-5686 5175);
PAINT MONO (-5686 5175);
FORCEPROP 2 LAST PATH I23
J 0
(-5575 5225);
DISPLAY 0.680851 (-5575 5225);
DISPLAY INVISIBLE (-5575 5225);
FORCEPROP 1 LAST COMMENT_BODY TRUE
J 0
(-5950 5075);
DISPLAY 0.872340 (-5950 5075);
PAINT PEACH (-5950 5075);
DISPLAY INVISIBLE (-5950 5075);
FORCEPROP 1 LAST OFFPAGE TRUE
J 0
(-5575 5050);
DISPLAY 0.872340 (-5575 5050);
PAINT GREEN (-5575 5050);
DISPLAY INVISIBLE (-5575 5050);
FORCEPROP 2 LAST CDS_LIB standard
J 2
(-5900 5175);
DISPLAY INVISIBLE (-5900 5175);
FORCEADD OFFPAGE..6
R 2
(-5900 5375);
FORCEPROP 2 LAST $XR1 80 
J 0
(-5596 5375);
DISPLAY 0.638298 (-5596 5375);
PAINT MONO (-5596 5375);
FORCEPROP 2 LAST $XR0 28 
J 0
(-5686 5375);
DISPLAY 0.638298 (-5686 5375);
PAINT MONO (-5686 5375);
FORCEPROP 2 LAST PATH I24
J 0
(-5575 5425);
DISPLAY 0.680851 (-5575 5425);
DISPLAY INVISIBLE (-5575 5425);
FORCEPROP 1 LAST COMMENT_BODY TRUE
J 2
(-6000 5300);
DISPLAY 0.872340 (-6000 5300);
PAINT GREEN (-6000 5300);
DISPLAY INVISIBLE (-6000 5300);
FORCEPROP 1 LAST OFFPAGE TRUE
J 2
(-6225 5250);
DISPLAY 0.872340 (-6225 5250);
PAINT GREEN (-6225 5250);
DISPLAY INVISIBLE (-6225 5250);
FORCEPROP 2 LAST CDS_LIB mstr_standard
J 2
(-5900 5375);
DISPLAY INVISIBLE (-5900 5375);
FORCEADD OFFPAGE..2
(-6800 2600);
FORCEPROP 2 LAST $XR0 119 
J 0
(-6611 2600);
DISPLAY 0.638298 (-6611 2600);
PAINT MONO (-6611 2600);
FORCEPROP 2 LAST PATH I25
J 0
(-6600 2650);
DISPLAY 0.680851 (-6600 2650);
DISPLAY INVISIBLE (-6600 2650);
FORCEPROP 1 LAST COMMENT_BODY TRUE
J 0
(-6845 2505);
DISPLAY 0.872340 (-6845 2505);
PAINT GREEN (-6845 2505);
DISPLAY INVISIBLE (-6845 2505);
FORCEPROP 1 LAST OFFPAGE TRUE
J 0
(-6475 2475);
DISPLAY 0.872340 (-6475 2475);
PAINT GREEN (-6475 2475);
DISPLAY INVISIBLE (-6475 2475);
FORCEPROP 2 LAST CDS_LIB standard
J 0
(-6800 2600);
DISPLAY INVISIBLE (-6800 2600);
FORCEADD OFFPAGE..2
(-6800 2650);
FORCEPROP 2 LAST $XR0 119 
J 0
(-6611 2650);
DISPLAY 0.638298 (-6611 2650);
PAINT MONO (-6611 2650);
FORCEPROP 2 LAST PATH I26
J 0
(-6600 2700);
DISPLAY 0.680851 (-6600 2700);
DISPLAY INVISIBLE (-6600 2700);
FORCEPROP 1 LAST COMMENT_BODY TRUE
J 0
(-6845 2555);
DISPLAY 0.872340 (-6845 2555);
PAINT GREEN (-6845 2555);
DISPLAY INVISIBLE (-6845 2555);
FORCEPROP 1 LAST OFFPAGE TRUE
J 0
(-6475 2525);
DISPLAY 0.872340 (-6475 2525);
PAINT GREEN (-6475 2525);
DISPLAY INVISIBLE (-6475 2525);
FORCEPROP 2 LAST CDS_LIB standard
J 0
(-6800 2650);
DISPLAY INVISIBLE (-6800 2650);
FORCEADD OFFPAGE..2
(-6800 2550);
FORCEPROP 2 LAST $XR0 119 
J 0
(-6611 2550);
DISPLAY 0.638298 (-6611 2550);
PAINT MONO (-6611 2550);
FORCEPROP 2 LAST PATH I27
J 0
(-6600 2600);
DISPLAY 0.680851 (-6600 2600);
DISPLAY INVISIBLE (-6600 2600);
FORCEPROP 1 LAST COMMENT_BODY TRUE
J 0
(-6845 2455);
DISPLAY 0.872340 (-6845 2455);
PAINT GREEN (-6845 2455);
DISPLAY INVISIBLE (-6845 2455);
FORCEPROP 1 LAST OFFPAGE TRUE
J 0
(-6475 2425);
DISPLAY 0.872340 (-6475 2425);
PAINT GREEN (-6475 2425);
DISPLAY INVISIBLE (-6475 2425);
FORCEPROP 2 LAST CDS_LIB standard
J 0
(-6800 2550);
DISPLAY INVISIBLE (-6800 2550);
FORCEADD OFFPAGE..2
(-6800 2500);
FORCEPROP 2 LAST $XR0 119 
J 0
(-6611 2500);
DISPLAY 0.638298 (-6611 2500);
PAINT MONO (-6611 2500);
FORCEPROP 2 LAST PATH I28
J 0
(-6600 2550);
DISPLAY 0.680851 (-6600 2550);
DISPLAY INVISIBLE (-6600 2550);
FORCEPROP 1 LAST COMMENT_BODY TRUE
J 0
(-6845 2405);
DISPLAY 0.872340 (-6845 2405);
PAINT GREEN (-6845 2405);
DISPLAY INVISIBLE (-6845 2405);
FORCEPROP 1 LAST OFFPAGE TRUE
J 0
(-6475 2375);
DISPLAY 0.872340 (-6475 2375);
PAINT GREEN (-6475 2375);
DISPLAY INVISIBLE (-6475 2375);
FORCEPROP 2 LAST CDS_LIB standard
J 0
(-6800 2500);
DISPLAY INVISIBLE (-6800 2500);
FORCEADD Q_RES..2
R 2
(-6725 5275);
FORCEPROP 1 LAST LOCATION R530
J 2
(-6770 5400);
DISPLAY 0.489362 (-6770 5400);
PAINT SKYBLUE (-6770 5400);
FORCEPROP 0 LAST $SEC 1
J 0
(-6750 5450);
DISPLAY 0.680851 (-6750 5450);
PAINT MONO (-6750 5450);
DISPLAY INVISIBLE (-6750 5450);
FORCEPROP 0 LAST CDS_SEC 1
J 0
(-6750 5450);
DISPLAY 0.680851 (-6750 5450);
DISPLAY INVISIBLE (-6750 5450);
FORCEPROP 1 LASTPIN (-6725 5375) $PN 1
J 2
(-6730 5337);
DISPLAY 0.489362 (-6730 5337);
PAINT MONO (-6730 5337);
FORCEPROP 1 LASTPIN (-6725 5175) $PN 2
J 2
(-6730 5185);
DISPLAY 0.489362 (-6730 5185);
PAINT MONO (-6730 5185);
FORCEPROP 1 LAST PACK_TYPE 0402LF
J 2
(-6775 5225);
DISPLAY 0.489362 (-6775 5225);
PAINT SKYBLUE (-6775 5225);
FORCEPROP 1 LAST VALUE 0
J 2
(-6775 5275);
DISPLAY 0.489362 (-6775 5275);
PAINT SKYBLUE (-6775 5275);
FORCEPROP 1 LAST MATERIAL CHIP
J 2
(-6775 5175);
DISPLAY 0.489362 (-6775 5175);
PAINT SKYBLUE (-6775 5175);
FORCEPROP 1 LAST PART_NUMBER CS00002JB38
J 2
(-6765 5150);
DISPLAY 0.638298 (-6765 5150);
PAINT SKYBLUE (-6765 5150);
DISPLAY INVISIBLE (-6765 5150);
FORCEPROP 1 LAST TOLERANCE 5%
J 2
(-6770 5300);
DISPLAY 0.638298 (-6770 5300);
PAINT SKYBLUE (-6770 5300);
DISPLAY INVISIBLE (-6770 5300);
FORCEPROP 1 LAST WATTAGE 1/16W
J 2
(-6765 5250);
DISPLAY 0.638298 (-6765 5250);
PAINT SKYBLUE (-6765 5250);
DISPLAY INVISIBLE (-6765 5250);
FORCEPROP 1 LAST PATH I29
J 2
(-6775 5450);
DISPLAY 0.978723 (-6775 5450);
PAINT WHITE (-6775 5450);
DISPLAY INVISIBLE (-6775 5450);
FORCEPROP 2 LAST CDS_LIB pure_quanta
J 2
(-6725 5275);
DISPLAY INVISIBLE (-6725 5275);
FORCEADD Q_CAP..1
(-1900 2175);
FORCEPROP 1 LAST LOCATION C20
J 0
(-2075 2275);
DISPLAY 0.489362 (-2075 2275);
PAINT SKYBLUE (-2075 2275);
FORCEPROP 0 LAST $SEC 1
J 0
(-2075 2325);
DISPLAY 0.680851 (-2075 2325);
PAINT MONO (-2075 2325);
DISPLAY INVISIBLE (-2075 2325);
FORCEPROP 0 LAST CDS_SEC 1
J 0
(-2075 2325);
DISPLAY 1.021277 (-2075 2325);
DISPLAY INVISIBLE (-2075 2325);
FORCEPROP 1 LASTPIN (-1900 2275) $PN 1
J 0
(-1890 2255);
DISPLAY 0.489362 (-1890 2255);
PAINT MONO (-1890 2255);
FORCEPROP 1 LASTPIN (-1900 2075) $PN 2
J 0
(-1890 2055);
DISPLAY 0.489362 (-1890 2055);
PAINT MONO (-1890 2055);
FORCEPROP 1 LAST PACK_TYPE C0402
J 0
(-2125 2025);
DISPLAY 0.489362 (-2125 2025);
PAINT SKYBLUE (-2125 2025);
FORCEPROP 1 LAST VOLTAGE 16V
J 0
(-2075 2175);
DISPLAY 0.489362 (-2075 2175);
PAINT SKYBLUE (-2075 2175);
FORCEPROP 1 LAST PART_NUMBER CH4103K1B08
J 0
(-2250 2075);
DISPLAY 0.489362 (-2250 2075);
PAINT SKYBLUE (-2250 2075);
FORCEPROP 1 LAST VALUE 0.1UF
J 0
(-2125 2225);
DISPLAY 0.489362 (-2125 2225);
PAINT SKYBLUE (-2125 2225);
FORCEPROP 1 LAST TOLERANCE 10%
J 0
(-2075 2125);
DISPLAY 0.489362 (-2075 2125);
PAINT SKYBLUE (-2075 2125);
FORCEPROP 1 LAST MATERIAL X7R
J 0
(-2075 1975);
DISPLAY 0.489362 (-2075 1975);
PAINT SKYBLUE (-2075 1975);
FORCEPROP 1 LAST PATH I3
J 0
(-1850 2325);
DISPLAY 0.978723 (-1850 2325);
PAINT WHITE (-1850 2325);
DISPLAY INVISIBLE (-1850 2325);
FORCEPROP 2 LAST CDS_LIB pure_quanta
J 0
(-1900 2175);
DISPLAY INVISIBLE (-1900 2175);
FORCEADD OFFPAGE..1
R 2
(-7575 5375);
FORCEPROP 2 LAST $XR2 77 
J 0
(-7209 5375);
DISPLAY 0.638298 (-7209 5375);
PAINT MONO (-7209 5375);
FORCEPROP 2 LAST $XR1 80 
J 0
(-7299 5375);
DISPLAY 0.638298 (-7299 5375);
PAINT MONO (-7299 5375);
FORCEPROP 2 LAST $XR0 28 
J 0
(-7389 5375);
DISPLAY 0.638298 (-7389 5375);
PAINT MONO (-7389 5375);
FORCEPROP 2 LAST PATH I30
J 0
(-7200 5425);
DISPLAY 0.680851 (-7200 5425);
DISPLAY INVISIBLE (-7200 5425);
FORCEPROP 1 LAST COMMENT_BODY TRUE
J 2
(-7700 5275);
DISPLAY 0.872340 (-7700 5275);
PAINT GREEN (-7700 5275);
DISPLAY INVISIBLE (-7700 5275);
FORCEPROP 1 LAST OFFPAGE TRUE
J 2
(-7900 5250);
DISPLAY 0.872340 (-7900 5250);
PAINT GREEN (-7900 5250);
DISPLAY INVISIBLE (-7900 5250);
FORCEPROP 2 LAST CDS_LIB standard
J 0
(-7575 5375);
DISPLAY INVISIBLE (-7575 5375);
FORCEADD OFFPAGE..2
(-7575 5175);
FORCEPROP 2 LAST $XR2 77 
J 0
(-7206 5175);
DISPLAY 0.638298 (-7206 5175);
PAINT MONO (-7206 5175);
FORCEPROP 2 LAST $XR1 80 
J 0
(-7296 5175);
DISPLAY 0.638298 (-7296 5175);
PAINT MONO (-7296 5175);
FORCEPROP 2 LAST $XR0 55 
J 0
(-7386 5175);
DISPLAY 0.638298 (-7386 5175);
PAINT MONO (-7386 5175);
FORCEPROP 2 LAST PATH I31
J 0
(-7200 5225);
DISPLAY 0.680851 (-7200 5225);
DISPLAY INVISIBLE (-7200 5225);
FORCEPROP 1 LAST COMMENT_BODY TRUE
J 0
(-7620 5080);
DISPLAY 0.872340 (-7620 5080);
PAINT GREEN (-7620 5080);
DISPLAY INVISIBLE (-7620 5080);
FORCEPROP 1 LAST OFFPAGE TRUE
J 0
(-7250 5050);
DISPLAY 0.872340 (-7250 5050);
PAINT GREEN (-7250 5050);
DISPLAY INVISIBLE (-7250 5050);
FORCEPROP 2 LAST CDS_LIB standard
J 0
(-7575 5175);
DISPLAY INVISIBLE (-7575 5175);
FORCEADD Q_RES..1
(-7575 2550);
FORCEPROP 1 LAST LOCATION R905
J 0
(-7475 2550);
DISPLAY 0.489362 (-7475 2550);
PAINT SKYBLUE (-7475 2550);
FORCEPROP 0 LAST $SEC 1
J 0
(-7475 2600);
DISPLAY 0.680851 (-7475 2600);
PAINT MONO (-7475 2600);
DISPLAY INVISIBLE (-7475 2600);
FORCEPROP 0 LAST CDS_SEC 1
J 0
(-7475 2600);
DISPLAY 0.680851 (-7475 2600);
DISPLAY INVISIBLE (-7475 2600);
FORCEPROP 1 LASTPIN (-7675 2550) $PN 1
J 0
(-7663 2562);
DISPLAY 0.489362 (-7663 2562);
PAINT MONO (-7663 2562);
FORCEPROP 1 LASTPIN (-7475 2550) $PN 2
J 0
(-7513 2562);
DISPLAY 0.489362 (-7513 2562);
PAINT MONO (-7513 2562);
FORCEPROP 1 LAST VALUE 0
J 2
(-7700 2550);
DISPLAY 0.489362 (-7700 2550);
PAINT SKYBLUE (-7700 2550);
FORCEPROP 2 LAST ROOM RST_CPU0_PLD_TO_DIMM
J 2
(-7550 2650);
DISPLAY 0.744681 (-7550 2650);
PAINT RED (-7550 2650);
DISPLAY INVISIBLE (-7550 2650);
FORCEPROP 1 LAST PACK_TYPE 0402LF
J 2
(-7400 2475);
DISPLAY 0.489362 (-7400 2475);
PAINT SKYBLUE (-7400 2475);
DISPLAY INVISIBLE (-7400 2475);
FORCEPROP 1 LAST PART_NUMBER CS00002JB38
J 2
(-7475 2600);
DISPLAY 0.489362 (-7475 2600);
PAINT SKYBLUE (-7475 2600);
DISPLAY INVISIBLE (-7475 2600);
FORCEPROP 1 LAST TOLERANCE 5%
J 0
(-7700 2525);
DISPLAY 0.489362 (-7700 2525);
PAINT SKYBLUE (-7700 2525);
DISPLAY INVISIBLE (-7700 2525);
FORCEPROP 1 LAST MATERIAL CHIP
J 2
(-7400 2525);
DISPLAY 0.489362 (-7400 2525);
PAINT SKYBLUE (-7400 2525);
DISPLAY INVISIBLE (-7400 2525);
FORCEPROP 1 LAST WATTAGE 1/16W
J 2
(-7650 2475);
DISPLAY 0.489362 (-7650 2475);
PAINT SKYBLUE (-7650 2475);
DISPLAY INVISIBLE (-7650 2475);
FORCEPROP 1 LAST PATH I32
J 0
(-7625 2700);
DISPLAY 0.978723 (-7625 2700);
PAINT WHITE (-7625 2700);
DISPLAY INVISIBLE (-7625 2700);
FORCEPROP 2 LAST BOM_COST MEM
J 2
(-7550 2700);
DISPLAY 0.744681 (-7550 2700);
PAINT WHITE (-7550 2700);
DISPLAY INVISIBLE (-7550 2700);
FORCEPROP 2 LAST CDS_LIB pure_quanta
J 0
(-7575 2550);
DISPLAY INVISIBLE (-7575 2550);
FORCEADD Q_RES..1
(-7575 2500);
FORCEPROP 1 LAST LOCATION R956
J 0
(-7475 2500);
DISPLAY 0.489362 (-7475 2500);
PAINT SKYBLUE (-7475 2500);
FORCEPROP 0 LAST $SEC 1
J 0
(-7475 2550);
DISPLAY 0.680851 (-7475 2550);
PAINT MONO (-7475 2550);
DISPLAY INVISIBLE (-7475 2550);
FORCEPROP 0 LAST CDS_SEC 1
J 0
(-7475 2550);
DISPLAY 0.680851 (-7475 2550);
DISPLAY INVISIBLE (-7475 2550);
FORCEPROP 1 LASTPIN (-7675 2500) $PN 1
J 0
(-7663 2512);
DISPLAY 0.489362 (-7663 2512);
PAINT MONO (-7663 2512);
FORCEPROP 1 LASTPIN (-7475 2500) $PN 2
J 0
(-7513 2512);
DISPLAY 0.489362 (-7513 2512);
PAINT MONO (-7513 2512);
FORCEPROP 1 LAST VALUE 0
J 2
(-7700 2500);
DISPLAY 0.489362 (-7700 2500);
PAINT SKYBLUE (-7700 2500);
FORCEPROP 2 LAST ROOM RST_CPU0_PLD_TO_DIMM
J 2
(-7550 2600);
DISPLAY 0.744681 (-7550 2600);
PAINT RED (-7550 2600);
DISPLAY INVISIBLE (-7550 2600);
FORCEPROP 1 LAST PACK_TYPE 0402LF
J 2
(-7400 2425);
DISPLAY 0.489362 (-7400 2425);
PAINT SKYBLUE (-7400 2425);
DISPLAY INVISIBLE (-7400 2425);
FORCEPROP 1 LAST PART_NUMBER CS00002JB38
J 2
(-7475 2550);
DISPLAY 0.489362 (-7475 2550);
PAINT SKYBLUE (-7475 2550);
DISPLAY INVISIBLE (-7475 2550);
FORCEPROP 1 LAST TOLERANCE 5%
J 0
(-7700 2475);
DISPLAY 0.489362 (-7700 2475);
PAINT SKYBLUE (-7700 2475);
DISPLAY INVISIBLE (-7700 2475);
FORCEPROP 1 LAST MATERIAL CHIP
J 2
(-7400 2475);
DISPLAY 0.489362 (-7400 2475);
PAINT SKYBLUE (-7400 2475);
DISPLAY INVISIBLE (-7400 2475);
FORCEPROP 1 LAST WATTAGE 1/16W
J 2
(-7650 2425);
DISPLAY 0.489362 (-7650 2425);
PAINT SKYBLUE (-7650 2425);
DISPLAY INVISIBLE (-7650 2425);
FORCEPROP 1 LAST PATH I33
J 0
(-7625 2650);
DISPLAY 0.978723 (-7625 2650);
PAINT WHITE (-7625 2650);
DISPLAY INVISIBLE (-7625 2650);
FORCEPROP 2 LAST BOM_COST MEM
J 2
(-7550 2650);
DISPLAY 0.744681 (-7550 2650);
PAINT WHITE (-7550 2650);
DISPLAY INVISIBLE (-7550 2650);
FORCEPROP 2 LAST CDS_LIB pure_quanta
J 0
(-7575 2500);
DISPLAY INVISIBLE (-7575 2500);
FORCEADD Q_RES..1
(-7575 2650);
FORCEPROP 1 LAST LOCATION R877
J 0
(-7475 2650);
DISPLAY 0.489362 (-7475 2650);
PAINT SKYBLUE (-7475 2650);
FORCEPROP 0 LAST $SEC 1
J 0
(-7475 2700);
DISPLAY 0.680851 (-7475 2700);
PAINT MONO (-7475 2700);
DISPLAY INVISIBLE (-7475 2700);
FORCEPROP 0 LAST CDS_SEC 1
J 0
(-7475 2700);
DISPLAY 0.680851 (-7475 2700);
DISPLAY INVISIBLE (-7475 2700);
FORCEPROP 1 LASTPIN (-7675 2650) $PN 1
J 0
(-7663 2662);
DISPLAY 0.489362 (-7663 2662);
PAINT MONO (-7663 2662);
FORCEPROP 1 LASTPIN (-7475 2650) $PN 2
J 0
(-7513 2662);
DISPLAY 0.489362 (-7513 2662);
PAINT MONO (-7513 2662);
FORCEPROP 1 LAST VALUE 0
J 2
(-7700 2650);
DISPLAY 0.489362 (-7700 2650);
PAINT SKYBLUE (-7700 2650);
FORCEPROP 2 LAST ROOM RST_CPU0_PLD_TO_DIMM
J 2
(-7550 2750);
DISPLAY 0.744681 (-7550 2750);
PAINT RED (-7550 2750);
DISPLAY INVISIBLE (-7550 2750);
FORCEPROP 1 LAST PACK_TYPE 0402LF
J 2
(-7400 2575);
DISPLAY 0.489362 (-7400 2575);
PAINT SKYBLUE (-7400 2575);
DISPLAY INVISIBLE (-7400 2575);
FORCEPROP 1 LAST PART_NUMBER CS00002JB38
J 2
(-7475 2700);
DISPLAY 0.489362 (-7475 2700);
PAINT SKYBLUE (-7475 2700);
DISPLAY INVISIBLE (-7475 2700);
FORCEPROP 1 LAST TOLERANCE 5%
J 0
(-7700 2625);
DISPLAY 0.489362 (-7700 2625);
PAINT SKYBLUE (-7700 2625);
DISPLAY INVISIBLE (-7700 2625);
FORCEPROP 1 LAST MATERIAL CHIP
J 2
(-7400 2625);
DISPLAY 0.489362 (-7400 2625);
PAINT SKYBLUE (-7400 2625);
DISPLAY INVISIBLE (-7400 2625);
FORCEPROP 1 LAST WATTAGE 1/16W
J 2
(-7650 2575);
DISPLAY 0.489362 (-7650 2575);
PAINT SKYBLUE (-7650 2575);
DISPLAY INVISIBLE (-7650 2575);
FORCEPROP 1 LAST PATH I34
J 0
(-7625 2800);
DISPLAY 0.978723 (-7625 2800);
PAINT WHITE (-7625 2800);
DISPLAY INVISIBLE (-7625 2800);
FORCEPROP 2 LAST BOM_COST MEM
J 2
(-7550 2800);
DISPLAY 0.744681 (-7550 2800);
PAINT WHITE (-7550 2800);
DISPLAY INVISIBLE (-7550 2800);
FORCEPROP 2 LAST CDS_LIB pure_quanta
J 0
(-7575 2650);
DISPLAY INVISIBLE (-7575 2650);
FORCEADD Q_RES..1
(-7575 2600);
FORCEPROP 1 LAST LOCATION R899
J 0
(-7475 2600);
DISPLAY 0.489362 (-7475 2600);
PAINT SKYBLUE (-7475 2600);
FORCEPROP 0 LAST $SEC 1
J 0
(-7475 2650);
DISPLAY 0.680851 (-7475 2650);
PAINT MONO (-7475 2650);
DISPLAY INVISIBLE (-7475 2650);
FORCEPROP 0 LAST CDS_SEC 1
J 0
(-7475 2650);
DISPLAY 0.680851 (-7475 2650);
DISPLAY INVISIBLE (-7475 2650);
FORCEPROP 1 LASTPIN (-7675 2600) $PN 1
J 0
(-7663 2612);
DISPLAY 0.489362 (-7663 2612);
PAINT MONO (-7663 2612);
FORCEPROP 1 LASTPIN (-7475 2600) $PN 2
J 0
(-7513 2612);
DISPLAY 0.489362 (-7513 2612);
PAINT MONO (-7513 2612);
FORCEPROP 1 LAST VALUE 0
J 2
(-7700 2600);
DISPLAY 0.489362 (-7700 2600);
PAINT SKYBLUE (-7700 2600);
FORCEPROP 2 LAST ROOM RST_CPU0_PLD_TO_DIMM
J 2
(-7550 2700);
DISPLAY 0.744681 (-7550 2700);
PAINT RED (-7550 2700);
DISPLAY INVISIBLE (-7550 2700);
FORCEPROP 1 LAST PACK_TYPE 0402LF
J 2
(-7400 2525);
DISPLAY 0.489362 (-7400 2525);
PAINT SKYBLUE (-7400 2525);
DISPLAY INVISIBLE (-7400 2525);
FORCEPROP 1 LAST PART_NUMBER CS00002JB38
J 2
(-7475 2650);
DISPLAY 0.489362 (-7475 2650);
PAINT SKYBLUE (-7475 2650);
DISPLAY INVISIBLE (-7475 2650);
FORCEPROP 1 LAST TOLERANCE 5%
J 0
(-7700 2575);
DISPLAY 0.489362 (-7700 2575);
PAINT SKYBLUE (-7700 2575);
DISPLAY INVISIBLE (-7700 2575);
FORCEPROP 1 LAST MATERIAL CHIP
J 2
(-7400 2575);
DISPLAY 0.489362 (-7400 2575);
PAINT SKYBLUE (-7400 2575);
DISPLAY INVISIBLE (-7400 2575);
FORCEPROP 1 LAST WATTAGE 1/16W
J 2
(-7650 2525);
DISPLAY 0.489362 (-7650 2525);
PAINT SKYBLUE (-7650 2525);
DISPLAY INVISIBLE (-7650 2525);
FORCEPROP 1 LAST PATH I35
J 0
(-7625 2750);
DISPLAY 0.978723 (-7625 2750);
PAINT WHITE (-7625 2750);
DISPLAY INVISIBLE (-7625 2750);
FORCEPROP 2 LAST BOM_COST MEM
J 2
(-7550 2750);
DISPLAY 0.744681 (-7550 2750);
PAINT WHITE (-7550 2750);
DISPLAY INVISIBLE (-7550 2750);
FORCEPROP 2 LAST CDS_LIB pure_quanta
J 0
(-7575 2600);
DISPLAY INVISIBLE (-7575 2600);
FORCEADD Q_RES..2
R 2
(-8450 5275);
FORCEPROP 1 LAST LOCATION R1422
J 2
(-8500 5325);
DISPLAY 0.489362 (-8500 5325);
PAINT SKYBLUE (-8500 5325);
FORCEPROP 0 LAST $SEC 1
J 0
(-8500 5375);
DISPLAY 0.680851 (-8500 5375);
PAINT MONO (-8500 5375);
DISPLAY INVISIBLE (-8500 5375);
FORCEPROP 0 LAST CDS_SEC 1
J 0
(-8500 5375);
DISPLAY 0.680851 (-8500 5375);
DISPLAY INVISIBLE (-8500 5375);
FORCEPROP 1 LASTPIN (-8450 5375) $PN 1
J 2
(-8455 5337);
DISPLAY 0.489362 (-8455 5337);
PAINT MONO (-8455 5337);
FORCEPROP 1 LASTPIN (-8450 5175) $PN 2
J 2
(-8455 5185);
DISPLAY 0.489362 (-8455 5185);
PAINT MONO (-8455 5185);
FORCEPROP 1 LAST VALUE 0
J 2
(-8500 5275);
DISPLAY 0.489362 (-8500 5275);
PAINT SKYBLUE (-8500 5275);
FORCEPROP 1 LAST PACK_TYPE 0402LF
J 2
(-8500 5225);
DISPLAY 0.489362 (-8500 5225);
PAINT SKYBLUE (-8500 5225);
FORCEPROP 1 LAST MATERIAL CHIP
J 2
(-8500 5175);
DISPLAY 0.489362 (-8500 5175);
PAINT SKYBLUE (-8500 5175);
FORCEPROP 1 LAST PART_NUMBER CS00002JB38
J 2
(-8490 5150);
DISPLAY 0.638298 (-8490 5150);
PAINT SKYBLUE (-8490 5150);
DISPLAY INVISIBLE (-8490 5150);
FORCEPROP 1 LAST TOLERANCE 5%
J 2
(-8495 5300);
DISPLAY 0.638298 (-8495 5300);
PAINT SKYBLUE (-8495 5300);
DISPLAY INVISIBLE (-8495 5300);
FORCEPROP 1 LAST WATTAGE 1/16W
J 2
(-8490 5250);
DISPLAY 0.638298 (-8490 5250);
PAINT SKYBLUE (-8490 5250);
DISPLAY INVISIBLE (-8490 5250);
FORCEPROP 1 LAST PATH I36
J 2
(-8500 5450);
DISPLAY 0.978723 (-8500 5450);
PAINT WHITE (-8500 5450);
DISPLAY INVISIBLE (-8500 5450);
FORCEPROP 2 LAST CDS_LIB pure_quanta
J 2
(-8450 5275);
DISPLAY INVISIBLE (-8450 5275);
FORCEADD OFFPAGE..1
(-8450 2650);
FORCEPROP 2 LAST $XR0 80 
J 0
(-8671 2650);
DISPLAY 0.638298 (-8671 2650);
PAINT MONO (-8671 2650);
FORCEPROP 2 LAST PATH I37
J 0
(-8650 2700);
DISPLAY 0.680851 (-8650 2700);
DISPLAY INVISIBLE (-8650 2700);
FORCEPROP 1 LAST COMMENT_BODY TRUE
J 0
(-8320 2550);
DISPLAY 1.106383 (-8320 2550);
PAINT PEACH (-8320 2550);
DISPLAY INVISIBLE (-8320 2550);
FORCEPROP 1 LAST OFFPAGE TRUE
J 0
(-8120 2520);
PAINT GREEN (-8120 2520);
DISPLAY INVISIBLE (-8120 2520);
FORCEPROP 2 LAST CDS_LIB standard
J 0
(-8450 2650);
DISPLAY INVISIBLE (-8450 2650);
FORCEADD OFFPAGE..2
(-6300 2025);
FORCEPROP 2 LAST $XR0 124 
J 0
(-6111 2025);
DISPLAY 0.638298 (-6111 2025);
PAINT MONO (-6111 2025);
FORCEPROP 2 LAST PATH I38
J 0
(-6100 2075);
DISPLAY 0.680851 (-6100 2075);
DISPLAY INVISIBLE (-6100 2075);
FORCEPROP 2 LAST CDS_LIB standard
J 0
(-6300 2025);
DISPLAY INVISIBLE (-6300 2025);
FORCEPROP 1 LAST OFFPAGE TRUE
J 0
(-5975 1900);
DISPLAY 0.872340 (-5975 1900);
PAINT GREEN (-5975 1900);
DISPLAY INVISIBLE (-5975 1900);
FORCEPROP 1 LAST COMMENT_BODY TRUE
J 0
(-6345 1930);
DISPLAY 0.872340 (-6345 1930);
PAINT GREEN (-6345 1930);
DISPLAY INVISIBLE (-6345 1930);
FORCEADD OFFPAGE..2
(-6300 1975);
FORCEPROP 2 LAST $XR0 125 
J 0
(-6111 1975);
DISPLAY 0.638298 (-6111 1975);
PAINT MONO (-6111 1975);
FORCEPROP 2 LAST PATH I39
J 0
(-6100 2025);
DISPLAY 0.680851 (-6100 2025);
DISPLAY INVISIBLE (-6100 2025);
FORCEPROP 2 LAST CDS_LIB standard
J 0
(-6300 1975);
DISPLAY INVISIBLE (-6300 1975);
FORCEPROP 1 LAST OFFPAGE TRUE
J 0
(-5975 1850);
DISPLAY 0.872340 (-5975 1850);
PAINT GREEN (-5975 1850);
DISPLAY INVISIBLE (-5975 1850);
FORCEPROP 1 LAST COMMENT_BODY TRUE
J 0
(-6345 1880);
DISPLAY 0.872340 (-6345 1880);
PAINT GREEN (-6345 1880);
DISPLAY INVISIBLE (-6345 1880);
FORCEADD CONN8_HBB1081L200D8H..1
(-1525 1800);
FORCEPROP 1 LAST LOCATION J57
J 0
(-1575 2311);
DISPLAY 0.489362 (-1575 2311);
PAINT SKYBLUE (-1575 2311);
FORCEPROP 0 LAST $SEC 1
J 0
(-1575 2350);
DISPLAY 0.680851 (-1575 2350);
PAINT MONO (-1575 2350);
DISPLAY INVISIBLE (-1575 2350);
FORCEPROP 0 LAST CDS_SEC 1
J 0
(-1575 2350);
DISPLAY 1.021277 (-1575 2350);
DISPLAY INVISIBLE (-1575 2350);
FORCEPROP 0 LASTPIN (-1725 1975) $PN 1
J 2
(-1735 1985);
DISPLAY 0.489362 (-1735 1985);
PAINT MONO (-1735 1985);
FORCEPROP 0 LASTPIN (-1725 1925) $PN 2
J 2
(-1735 1935);
DISPLAY 0.489362 (-1735 1935);
PAINT MONO (-1735 1935);
FORCEPROP 0 LASTPIN (-1725 1875) $PN 3
J 2
(-1735 1885);
DISPLAY 0.489362 (-1735 1885);
PAINT MONO (-1735 1885);
FORCEPROP 0 LASTPIN (-1725 1825) $PN 4
J 2
(-1735 1835);
DISPLAY 0.489362 (-1735 1835);
PAINT MONO (-1735 1835);
FORCEPROP 0 LASTPIN (-1725 1775) $PN 5
J 2
(-1735 1785);
DISPLAY 0.489362 (-1735 1785);
PAINT MONO (-1735 1785);
FORCEPROP 0 LASTPIN (-1725 1725) $PN 6
J 2
(-1735 1735);
DISPLAY 0.489362 (-1735 1735);
PAINT MONO (-1735 1735);
FORCEPROP 0 LASTPIN (-1725 1675) $PN 7
J 2
(-1735 1685);
DISPLAY 0.489362 (-1735 1685);
PAINT MONO (-1735 1685);
FORCEPROP 0 LASTPIN (-1725 1625) $PN 8
J 2
(-1735 1635);
DISPLAY 0.489362 (-1735 1635);
PAINT MONO (-1735 1635);
FORCEPROP 1 LAST PART_NUMBER DFHD08MS197
J 0
(-1575 2100);
DISPLAY 0.489362 (-1575 2100);
PAINT SKYBLUE (-1575 2100);
FORCEPROP 2 LAST VALUE CONN8_HBB1081-L200D-8H
J 0
(-1575 2175);
DISPLAY 0.489362 (-1575 2175);
PAINT SKYBLUE (-1575 2175);
FORCEPROP 1 LAST MATERIAL IO
J 0
(-1575 2037);
DISPLAY 0.489362 (-1575 2037);
PAINT SKYBLUE (-1575 2037);
FORCEPROP 2 LAST PART_TYPE THLF
J 0
(-1575 2225);
DISPLAY 1.021277 (-1575 2225);
FORCEPROP 1 LAST PATH I4
J 0
(-1525 1800);
DISPLAY 0.723404 (-1525 1800);
PAINT GREEN (-1525 1800);
DISPLAY INVISIBLE (-1525 1800);
FORCEPROP 2 LAST CDS_LIB pure_quanta
J 0
(-1525 1800);
DISPLAY INVISIBLE (-1525 1800);
FORCEPROP 1 LAST NEEDS_NO_SIZE TRUE
J 0
(-1525 1800);
DISPLAY 0.723404 (-1525 1800);
PAINT GREEN (-1525 1800);
DISPLAY INVISIBLE (-1525 1800);
FORCEPROP 1 LAST CDS_LMAN_SYM_OUTLINE -50,225,50,-225
J 0
(-1525 1800);
DISPLAY 0.468085 (-1525 1800);
PAINT GREEN (-1525 1800);
DISPLAY INVISIBLE (-1525 1800);
FORCEADD OFFPAGE..2
(-6300 1925);
FORCEPROP 2 LAST $XR0 126 
J 0
(-6111 1925);
DISPLAY 0.638298 (-6111 1925);
PAINT MONO (-6111 1925);
FORCEPROP 2 LAST PATH I40
J 0
(-6100 1975);
DISPLAY 0.680851 (-6100 1975);
DISPLAY INVISIBLE (-6100 1975);
FORCEPROP 2 LAST CDS_LIB standard
J 0
(-6300 1925);
DISPLAY INVISIBLE (-6300 1925);
FORCEPROP 1 LAST OFFPAGE TRUE
J 0
(-5975 1800);
DISPLAY 0.872340 (-5975 1800);
PAINT GREEN (-5975 1800);
DISPLAY INVISIBLE (-5975 1800);
FORCEPROP 1 LAST COMMENT_BODY TRUE
J 0
(-6345 1830);
DISPLAY 0.872340 (-6345 1830);
PAINT GREEN (-6345 1830);
DISPLAY INVISIBLE (-6345 1830);
FORCEADD OFFPAGE..2
(-6300 1875);
FORCEPROP 2 LAST $XR0 127 
J 0
(-6111 1875);
DISPLAY 0.638298 (-6111 1875);
PAINT MONO (-6111 1875);
FORCEPROP 2 LAST PATH I41
J 0
(-6100 1925);
DISPLAY 0.680851 (-6100 1925);
DISPLAY INVISIBLE (-6100 1925);
FORCEPROP 2 LAST CDS_LIB standard
J 0
(-6300 1875);
DISPLAY INVISIBLE (-6300 1875);
FORCEPROP 1 LAST OFFPAGE TRUE
J 0
(-5975 1750);
DISPLAY 0.872340 (-5975 1750);
PAINT GREEN (-5975 1750);
DISPLAY INVISIBLE (-5975 1750);
FORCEPROP 1 LAST COMMENT_BODY TRUE
J 0
(-6345 1780);
DISPLAY 0.872340 (-6345 1780);
PAINT GREEN (-6345 1780);
DISPLAY INVISIBLE (-6345 1780);
FORCEADD VCC_CORE..1
R 5
(-7250 1800);
FORCEPROP 3 LASTPIN (-7300 1800) SIG_NAME P3V3_STBY\g
J 0
(-7290 1810);
DISPLAY 0.659574 (-7290 1810);
PAINT MONO (-7290 1810);
DISPLAY INVISIBLE (-7290 1810);
FORCEPROP 1 LAST HDL_POWER P3V3_STBY
J 1
(-7075 1800);
DISPLAY 0.489362 (-7075 1800);
PAINT GREEN (-7075 1800);
FORCEPROP 1 LAST PATH I42
R 3
J 0
(-7225 1750);
DISPLAY 0.872340 (-7225 1750);
PAINT AQUA (-7225 1750);
DISPLAY INVISIBLE (-7225 1750);
FORCEPROP 2 LAST CDS_LIB pure_quanta_power
R 3
J 0
(-7250 1800);
DISPLAY INVISIBLE (-7250 1800);
FORCEADD Q_RES..1
(-7675 2025);
FORCEPROP 1 LAST LOCATION R1036
J 0
(-7875 2025);
DISPLAY 0.489362 (-7875 2025);
PAINT SKYBLUE (-7875 2025);
FORCEPROP 2 LAST $SEC 1
J 0
(-7725 2225);
DISPLAY 0.680851 (-7725 2225);
PAINT MONO (-7725 2225);
DISPLAY INVISIBLE (-7725 2225);
FORCEPROP 2 LAST CDS_SEC 1
J 0
(-7725 2225);
DISPLAY 0.680851 (-7725 2225);
DISPLAY INVISIBLE (-7725 2225);
FORCEPROP 1 LASTPIN (-7775 2025) $PN 1
J 0
(-7763 2037);
DISPLAY 0.489362 (-7763 2037);
PAINT MONO (-7763 2037);
FORCEPROP 1 LASTPIN (-7575 2025) $PN 2
J 0
(-7613 2037);
DISPLAY 0.489362 (-7613 2037);
PAINT MONO (-7613 2037);
FORCEPROP 1 LAST VALUE 0
J 2
(-7450 2025);
DISPLAY 0.489362 (-7450 2025);
PAINT SKYBLUE (-7450 2025);
FORCEPROP 1 LAST MATERIAL CHIP
J 0
(-7400 2025);
DISPLAY 0.489362 (-7400 2025);
PAINT SKYBLUE (-7400 2025);
FORCEPROP 1 LAST PACK_TYPE 0402LF
J 0
(-7600 1975);
DISPLAY 0.489362 (-7600 1975);
PAINT SKYBLUE (-7600 1975);
DISPLAY INVISIBLE (-7600 1975);
FORCEPROP 1 LAST PART_NUMBER CS00002JB38
J 0
(-7600 2075);
DISPLAY 0.489362 (-7600 2075);
PAINT SKYBLUE (-7600 2075);
DISPLAY INVISIBLE (-7600 2075);
FORCEPROP 1 LAST TOLERANCE 5%
J 0
(-7675 1975);
DISPLAY 0.489362 (-7675 1975);
PAINT SKYBLUE (-7675 1975);
DISPLAY INVISIBLE (-7675 1975);
FORCEPROP 1 LAST WATTAGE 1/16W
J 2
(-7700 1925);
DISPLAY 0.489362 (-7700 1925);
PAINT SKYBLUE (-7700 1925);
DISPLAY INVISIBLE (-7700 1925);
FORCEPROP 1 LAST PATH I43
J 0
(-7725 2175);
DISPLAY 0.978723 (-7725 2175);
PAINT WHITE (-7725 2175);
DISPLAY INVISIBLE (-7725 2175);
FORCEPROP 2 LAST BOM_COST OCP3.0 
J 0
(-7600 2125);
DISPLAY 0.680851 (-7600 2125);
DISPLAY INVISIBLE (-7600 2125);
FORCEPROP 2 LAST CDS_LIB pure_quanta
J 0
(-7675 2025);
DISPLAY INVISIBLE (-7675 2025);
FORCEADD Q_RES..1
(-7675 1975);
FORCEPROP 1 LAST LOCATION R1292
J 0
(-7875 1975);
DISPLAY 0.489362 (-7875 1975);
PAINT SKYBLUE (-7875 1975);
FORCEPROP 0 LAST $SEC 1
J 0
(-7800 2025);
DISPLAY 0.680851 (-7800 2025);
PAINT MONO (-7800 2025);
DISPLAY INVISIBLE (-7800 2025);
FORCEPROP 0 LAST CDS_SEC 1
J 0
(-7800 2025);
DISPLAY 0.680851 (-7800 2025);
DISPLAY INVISIBLE (-7800 2025);
FORCEPROP 1 LASTPIN (-7775 1975) $PN 1
J 0
(-7763 1987);
DISPLAY 0.489362 (-7763 1987);
PAINT MONO (-7763 1987);
FORCEPROP 1 LASTPIN (-7575 1975) $PN 2
J 0
(-7613 1987);
DISPLAY 0.489362 (-7613 1987);
PAINT MONO (-7613 1987);
FORCEPROP 1 LAST VALUE 0
J 2
(-7450 1975);
DISPLAY 0.489362 (-7450 1975);
PAINT SKYBLUE (-7450 1975);
FORCEPROP 1 LAST MATERIAL CHIP
J 0
(-7400 1975);
DISPLAY 0.489362 (-7400 1975);
PAINT SKYBLUE (-7400 1975);
FORCEPROP 1 LAST PACK_TYPE 0402LF
J 0
(-7600 1925);
DISPLAY 0.489362 (-7600 1925);
PAINT SKYBLUE (-7600 1925);
DISPLAY INVISIBLE (-7600 1925);
FORCEPROP 1 LAST PART_NUMBER CS00002JB38
J 0
(-7600 2025);
DISPLAY 0.489362 (-7600 2025);
PAINT SKYBLUE (-7600 2025);
DISPLAY INVISIBLE (-7600 2025);
FORCEPROP 1 LAST TOLERANCE 5%
J 0
(-7675 1925);
DISPLAY 0.489362 (-7675 1925);
PAINT SKYBLUE (-7675 1925);
DISPLAY INVISIBLE (-7675 1925);
FORCEPROP 1 LAST WATTAGE 1/16W
J 2
(-7700 1875);
DISPLAY 0.489362 (-7700 1875);
PAINT SKYBLUE (-7700 1875);
DISPLAY INVISIBLE (-7700 1875);
FORCEPROP 1 LAST PATH I44
J 0
(-7725 2125);
DISPLAY 0.978723 (-7725 2125);
PAINT WHITE (-7725 2125);
DISPLAY INVISIBLE (-7725 2125);
FORCEPROP 2 LAST BOM_COST OCP3.0 
J 0
(-7600 2075);
DISPLAY 0.680851 (-7600 2075);
DISPLAY INVISIBLE (-7600 2075);
FORCEPROP 2 LAST CDS_LIB pure_quanta
J 0
(-7675 1975);
DISPLAY INVISIBLE (-7675 1975);
FORCEADD Q_RES..1
(-7675 1925);
FORCEPROP 1 LAST LOCATION R1301
J 0
(-7875 1925);
DISPLAY 0.489362 (-7875 1925);
PAINT SKYBLUE (-7875 1925);
FORCEPROP 0 LAST $SEC 1
J 0
(-7800 1975);
DISPLAY 0.680851 (-7800 1975);
PAINT MONO (-7800 1975);
DISPLAY INVISIBLE (-7800 1975);
FORCEPROP 0 LAST CDS_SEC 1
J 0
(-7800 1975);
DISPLAY 0.680851 (-7800 1975);
DISPLAY INVISIBLE (-7800 1975);
FORCEPROP 1 LASTPIN (-7775 1925) $PN 1
J 0
(-7763 1937);
DISPLAY 0.489362 (-7763 1937);
PAINT MONO (-7763 1937);
FORCEPROP 1 LASTPIN (-7575 1925) $PN 2
J 0
(-7613 1937);
DISPLAY 0.489362 (-7613 1937);
PAINT MONO (-7613 1937);
FORCEPROP 1 LAST VALUE 0
J 2
(-7450 1925);
DISPLAY 0.489362 (-7450 1925);
PAINT SKYBLUE (-7450 1925);
FORCEPROP 1 LAST MATERIAL CHIP
J 0
(-7400 1925);
DISPLAY 0.489362 (-7400 1925);
PAINT SKYBLUE (-7400 1925);
FORCEPROP 1 LAST PACK_TYPE 0402LF
J 0
(-7600 1875);
DISPLAY 0.489362 (-7600 1875);
PAINT SKYBLUE (-7600 1875);
DISPLAY INVISIBLE (-7600 1875);
FORCEPROP 1 LAST PART_NUMBER CS00002JB38
J 0
(-7600 1975);
DISPLAY 0.489362 (-7600 1975);
PAINT SKYBLUE (-7600 1975);
DISPLAY INVISIBLE (-7600 1975);
FORCEPROP 1 LAST TOLERANCE 5%
J 0
(-7675 1875);
DISPLAY 0.489362 (-7675 1875);
PAINT SKYBLUE (-7675 1875);
DISPLAY INVISIBLE (-7675 1875);
FORCEPROP 1 LAST WATTAGE 1/16W
J 2
(-7700 1825);
DISPLAY 0.489362 (-7700 1825);
PAINT SKYBLUE (-7700 1825);
DISPLAY INVISIBLE (-7700 1825);
FORCEPROP 1 LAST PATH I45
J 0
(-7725 2075);
DISPLAY 0.978723 (-7725 2075);
PAINT WHITE (-7725 2075);
DISPLAY INVISIBLE (-7725 2075);
FORCEPROP 2 LAST BOM_COST OCP3.0 
J 0
(-7600 2025);
DISPLAY 0.680851 (-7600 2025);
DISPLAY INVISIBLE (-7600 2025);
FORCEPROP 2 LAST CDS_LIB pure_quanta
J 0
(-7675 1925);
DISPLAY INVISIBLE (-7675 1925);
FORCEADD Q_RES..1
(-7675 1875);
FORCEPROP 1 LAST LOCATION R1302
J 0
(-7875 1875);
DISPLAY 0.489362 (-7875 1875);
PAINT SKYBLUE (-7875 1875);
FORCEPROP 0 LAST $SEC 1
J 0
(-7800 1925);
DISPLAY 0.680851 (-7800 1925);
PAINT MONO (-7800 1925);
DISPLAY INVISIBLE (-7800 1925);
FORCEPROP 0 LAST CDS_SEC 1
J 0
(-7800 1925);
DISPLAY 0.680851 (-7800 1925);
DISPLAY INVISIBLE (-7800 1925);
FORCEPROP 1 LASTPIN (-7775 1875) $PN 1
J 0
(-7763 1887);
DISPLAY 0.489362 (-7763 1887);
PAINT MONO (-7763 1887);
FORCEPROP 1 LASTPIN (-7575 1875) $PN 2
J 0
(-7613 1887);
DISPLAY 0.489362 (-7613 1887);
PAINT MONO (-7613 1887);
FORCEPROP 1 LAST VALUE 0
J 2
(-7450 1875);
DISPLAY 0.489362 (-7450 1875);
PAINT SKYBLUE (-7450 1875);
FORCEPROP 1 LAST MATERIAL CHIP
J 0
(-7400 1875);
DISPLAY 0.489362 (-7400 1875);
PAINT SKYBLUE (-7400 1875);
FORCEPROP 1 LAST PACK_TYPE 0402LF
J 0
(-7600 1825);
DISPLAY 0.489362 (-7600 1825);
PAINT SKYBLUE (-7600 1825);
DISPLAY INVISIBLE (-7600 1825);
FORCEPROP 1 LAST PART_NUMBER CS00002JB38
J 0
(-7600 1925);
DISPLAY 0.489362 (-7600 1925);
PAINT SKYBLUE (-7600 1925);
DISPLAY INVISIBLE (-7600 1925);
FORCEPROP 1 LAST TOLERANCE 5%
J 0
(-7675 1825);
DISPLAY 0.489362 (-7675 1825);
PAINT SKYBLUE (-7675 1825);
DISPLAY INVISIBLE (-7675 1825);
FORCEPROP 1 LAST WATTAGE 1/16W
J 2
(-7700 1775);
DISPLAY 0.489362 (-7700 1775);
PAINT SKYBLUE (-7700 1775);
DISPLAY INVISIBLE (-7700 1775);
FORCEPROP 1 LAST PATH I46
J 0
(-7725 2025);
DISPLAY 0.978723 (-7725 2025);
PAINT WHITE (-7725 2025);
DISPLAY INVISIBLE (-7725 2025);
FORCEPROP 2 LAST BOM_COST OCP3.0 
J 0
(-7600 1975);
DISPLAY 0.680851 (-7600 1975);
DISPLAY INVISIBLE (-7600 1975);
FORCEPROP 2 LAST CDS_LIB pure_quanta
J 0
(-7675 1875);
DISPLAY INVISIBLE (-7675 1875);
FORCEADD Q_RES..1
(-7675 1800);
FORCEPROP 1 LAST LOCATION R1303
J 0
(-7875 1800);
DISPLAY 0.489362 (-7875 1800);
PAINT SKYBLUE (-7875 1800);
FORCEPROP 0 LAST $SEC 1
J 0
(-7525 1850);
DISPLAY 0.680851 (-7525 1850);
PAINT MONO (-7525 1850);
DISPLAY INVISIBLE (-7525 1850);
FORCEPROP 0 LAST CDS_SEC 1
J 0
(-7525 1850);
DISPLAY 0.680851 (-7525 1850);
DISPLAY INVISIBLE (-7525 1850);
FORCEPROP 1 LASTPIN (-7775 1800) $PN 1
J 0
(-7763 1812);
DISPLAY 0.489362 (-7763 1812);
PAINT MONO (-7763 1812);
FORCEPROP 1 LASTPIN (-7575 1800) $PN 2
J 0
(-7613 1812);
DISPLAY 0.489362 (-7613 1812);
PAINT MONO (-7613 1812);
FORCEPROP 1 LAST VALUE 4.7K
J 0
(-7475 1800);
DISPLAY 0.489362 (-7475 1800);
PAINT SKYBLUE (-7475 1800);
FORCEPROP 1 LAST WATTAGE 1/16W
J 2
(-7700 1650);
DISPLAY 0.510638 (-7700 1650);
PAINT SKYBLUE (-7700 1650);
DISPLAY INVISIBLE (-7700 1650);
FORCEPROP 1 LAST MATERIAL CHIP
J 0
(-7575 1775);
DISPLAY 0.489362 (-7575 1775);
PAINT SKYBLUE (-7575 1775);
DISPLAY INVISIBLE (-7575 1775);
FORCEPROP 1 LAST TOLERANCE 5%
J 0
(-7550 1800);
DISPLAY 0.510638 (-7550 1800);
PAINT SKYBLUE (-7550 1800);
DISPLAY INVISIBLE (-7550 1800);
FORCEPROP 1 LAST PART_NUMBER TMP_QCS24702JB38
J 0
(-7725 1900);
DISPLAY 0.510638 (-7725 1900);
PAINT SKYBLUE (-7725 1900);
DISPLAY INVISIBLE (-7725 1900);
FORCEPROP 1 LAST PACK_TYPE 0402LF
J 0
(-7425 1650);
DISPLAY 0.510638 (-7425 1650);
PAINT SKYBLUE (-7425 1650);
DISPLAY INVISIBLE (-7425 1650);
FORCEPROP 1 LAST PATH I47
J 0
(-7725 1950);
DISPLAY 0.978723 (-7725 1950);
PAINT WHITE (-7725 1950);
DISPLAY INVISIBLE (-7725 1950);
FORCEPROP 2 LAST CDS_LIB pure_quanta
J 0
(-7675 1800);
DISPLAY INVISIBLE (-7675 1800);
FORCEADD OFFPAGE..1
(-8425 2025);
FORCEPROP 2 LASTPIN (-8375 2025) SIG_NAME FM_SMB_RST_E1S_1_N
J 0
(-8385 2035);
DISPLAY 0.489362 (-8385 2035);
FORCEPROP 2 LAST $XR0 81 
J 0
(-8646 2025);
DISPLAY 0.638298 (-8646 2025);
PAINT MONO (-8646 2025);
FORCEPROP 1 LAST COMMENT_BODY TRUE
J 0
(-8300 1925);
DISPLAY 0.872340 (-8300 1925);
PAINT GREEN (-8300 1925);
DISPLAY INVISIBLE (-8300 1925);
FORCEPROP 1 LAST OFFPAGE TRUE
J 0
(-8100 1900);
DISPLAY 0.872340 (-8100 1900);
PAINT GREEN (-8100 1900);
DISPLAY INVISIBLE (-8100 1900);
FORCEPROP 2 LAST PATH I48
J 0
(-8375 2100);
DISPLAY 0.680851 (-8375 2100);
DISPLAY INVISIBLE (-8375 2100);
FORCEPROP 2 LAST CDS_LIB standard
J 0
(-8425 2025);
DISPLAY INVISIBLE (-8425 2025);
FORCEADD OFFPAGE..1
R 2
(-825 4800);
FORCEPROP 2 LAST $XR0 80 
J 0
(-639 4800);
DISPLAY 0.638298 (-639 4800);
PAINT MONO (-639 4800);
FORCEPROP 2 LAST PATH I49
J 0
(-625 4850);
DISPLAY 0.680851 (-625 4850);
DISPLAY INVISIBLE (-625 4850);
FORCEPROP 1 LAST COMMENT_BODY TRUE
J 2
(-950 4700);
DISPLAY 0.872340 (-950 4700);
PAINT GREEN (-950 4700);
DISPLAY INVISIBLE (-950 4700);
FORCEPROP 1 LAST OFFPAGE TRUE
J 2
(-1150 4675);
DISPLAY 0.872340 (-1150 4675);
PAINT GREEN (-1150 4675);
DISPLAY INVISIBLE (-1150 4675);
FORCEPROP 2 LAST CDS_LIB standard
J 0
(-825 4800);
DISPLAY INVISIBLE (-825 4800);
FORCEADD UNIVERSAL_GND..1
(-1800 1500);
FORCEPROP 3 LASTPIN (-1800 1550) SIG_NAME GND\g
J 0
(-1790 1560);
DISPLAY 0.659574 (-1790 1560);
PAINT MONO (-1790 1560);
DISPLAY INVISIBLE (-1790 1560);
FORCEPROP 1 LAST HDL_POWER GND
J 1
(-1775 1425);
DISPLAY 0.872340 (-1775 1425);
PAINT GREEN (-1775 1425);
DISPLAY INVISIBLE (-1775 1425);
FORCEPROP 1 LAST PATH I5
J 0
(-1725 1500);
DISPLAY 0.872340 (-1725 1500);
PAINT AQUA (-1725 1500);
DISPLAY INVISIBLE (-1725 1500);
FORCEPROP 2 LAST CDS_LIB pure_quanta_power
J 0
(-1800 1500);
DISPLAY INVISIBLE (-1800 1500);
FORCEADD UNIVERSAL_GND..1
(-1450 4625);
FORCEPROP 3 LASTPIN (-1450 4675) SIG_NAME GND\g
J 0
(-1440 4685);
DISPLAY 0.659574 (-1440 4685);
PAINT MONO (-1440 4685);
DISPLAY INVISIBLE (-1440 4685);
FORCEPROP 1 LAST HDL_POWER GND
J 1
(-1425 4550);
DISPLAY 0.489362 (-1425 4550);
PAINT GREEN (-1425 4550);
FORCEPROP 1 LAST PATH I50
J 0
(-1375 4625);
DISPLAY 0.872340 (-1375 4625);
PAINT AQUA (-1375 4625);
DISPLAY INVISIBLE (-1375 4625);
FORCEPROP 2 LAST CDS_LIB pure_quanta_power
J 0
(-1450 4625);
DISPLAY INVISIBLE (-1450 4625);
FORCEPROP 2 LAST BOM_COST MISC.
J 0
(-1425 4600);
DISPLAY 0.680851 (-1425 4600);
DISPLAY INVISIBLE (-1425 4600);
FORCEADD Q_LED..1
(-2725 5500);
FORCEPROP 1 LAST LOCATION D7
J 0
(-2825 5685);
DISPLAY 0.489362 (-2825 5685);
PAINT SKYBLUE (-2825 5685);
FORCEPROP 0 LAST $SEC 1
J 0
(-2825 5725);
DISPLAY 0.680851 (-2825 5725);
PAINT MONO (-2825 5725);
DISPLAY INVISIBLE (-2825 5725);
FORCEPROP 0 LAST CDS_SEC 1
J 0
(-2825 5725);
DISPLAY 0.680851 (-2825 5725);
DISPLAY INVISIBLE (-2825 5725);
FORCEPROP 0 LASTPIN (-2875 5500) $PN A
J 2
(-2885 5510);
DISPLAY 0.489362 (-2885 5510);
PAINT MONO (-2885 5510);
FORCEPROP 0 LASTPIN (-2575 5500) $PN C
J 0
(-2565 5510);
DISPLAY 0.489362 (-2565 5510);
PAINT MONO (-2565 5510);
FORCEPROP 2 LAST PACK_TYPE SMLF
J 0
(-2900 5400);
DISPLAY 0.489362 (-2900 5400);
PAINT SKYBLUE (-2900 5400);
FORCEPROP 2 LAST COLOR LED_RED
J 0
(-2700 5400);
DISPLAY 0.489362 (-2700 5400);
FORCEPROP 1 LAST PART_NUMBER BERD0021Z02
J 0
(-2825 5635);
DISPLAY 0.489362 (-2825 5635);
PAINT SKYBLUE (-2825 5635);
FORCEPROP 1 LAST MATERIAL IC
J 0
(-2825 5580);
DISPLAY 0.489362 (-2825 5580);
PAINT SKYBLUE (-2825 5580);
FORCEPROP 1 LAST PATH I51
J 0
(-2600 5580);
DISPLAY 0.723404 (-2600 5580);
PAINT GREEN (-2600 5580);
DISPLAY INVISIBLE (-2600 5580);
FORCEPROP 0 LAST MANUF_PN LTST-C190KRKT
J 0
(-2900 5350);
DISPLAY 0.680851 (-2900 5350);
DISPLAY INVISIBLE (-2900 5350);
FORCEPROP 2 LAST CDS_LIB pure_quanta
J 0
(-2725 5500);
DISPLAY INVISIBLE (-2725 5500);
FORCEPROP 1 LAST NEEDS_NO_SIZE TRUE
J 0
(-2725 5500);
DISPLAY 0.468085 (-2725 5500);
PAINT GREEN (-2725 5500);
DISPLAY INVISIBLE (-2725 5500);
FORCEADD MOSFET_DUAL_6P..1
R 6
(-1850 4800);
FORCEPROP 1 LAST LOCATION Q28
J 0
(-2000 5014);
DISPLAY 0.489362 (-2000 5014);
PAINT SKYBLUE (-2000 5014);
FORCEPROP 0 LAST $SEC 1
J 0
(-2000 5125);
DISPLAY 0.680851 (-2000 5125);
PAINT MONO (-2000 5125);
DISPLAY INVISIBLE (-2000 5125);
FORCEPROP 0 LAST CDS_SEC 1
J 0
(-2000 5125);
DISPLAY 0.680851 (-2000 5125);
DISPLAY INVISIBLE (-2000 5125);
FORCEPROP 0 LASTPIN (-2150 4850) $PN 6
J 2
(-2160 4860);
DISPLAY 0.489362 (-2160 4860);
PAINT MONO (-2160 4860);
FORCEPROP 0 LASTPIN (-1550 4850) $PN 3
J 0
(-1540 4860);
DISPLAY 0.489362 (-1540 4860);
PAINT MONO (-1540 4860);
FORCEPROP 0 LASTPIN (-2150 4800) $PN 2
J 2
(-2160 4810);
DISPLAY 0.489362 (-2160 4810);
PAINT MONO (-2160 4810);
FORCEPROP 0 LASTPIN (-1550 4800) $PN 5
J 0
(-1540 4810);
DISPLAY 0.489362 (-1540 4810);
PAINT MONO (-1540 4810);
FORCEPROP 0 LASTPIN (-2150 4750) $PN 1
J 2
(-2160 4760);
DISPLAY 0.489362 (-2160 4760);
PAINT MONO (-2160 4760);
FORCEPROP 0 LASTPIN (-1550 4750) $PN 4
J 0
(-1540 4760);
DISPLAY 0.489362 (-1540 4760);
PAINT MONO (-1540 4760);
FORCEPROP 1 LAST PART_NUMBER BAM70020047
J 0
(-2000 5056);
DISPLAY 0.489362 (-2000 5056);
PAINT SKYBLUE (-2000 5056);
FORCEPROP 2 LAST VALUE 2N7002KDW
J 0
(-2000 4973);
DISPLAY 0.489362 (-2000 4973);
PAINT SKYBLUE (-2000 4973);
FORCEPROP 1 LAST MATERIAL IC
J 0
(-2000 5100);
DISPLAY 0.489362 (-2000 5100);
PAINT SKYBLUE (-2000 5100);
FORCEPROP 2 LAST PART_TYPE SMLF
J 0
(-2000 4914);
DISPLAY 0.680851 (-2000 4914);
FORCEPROP 1 LAST PATH I52
J 0
(-1850 4800);
DISPLAY 0.723404 (-1850 4800);
PAINT GREEN (-1850 4800);
DISPLAY INVISIBLE (-1850 4800);
FORCEPROP 1 LAST NEEDS_NO_SIZE TRUE
J 0
(-1850 4779);
DISPLAY 0.468085 (-1850 4779);
PAINT GREEN (-1850 4779);
DISPLAY INVISIBLE (-1850 4779);
FORCEPROP 1 LAST CDS_LMAN_SYM_OUTLINE -150,100,150,-100
J 0
(-1850 4778);
DISPLAY 0.468085 (-1850 4778);
PAINT GREEN (-1850 4778);
DISPLAY INVISIBLE (-1850 4778);
FORCEPROP 2 LAST CDS_LIB pure_quanta
J 0
(-1850 4753);
DISPLAY INVISIBLE (-1850 4753);
FORCEADD UNIVERSAL_GND..1
(-2225 4625);
FORCEPROP 3 LASTPIN (-2225 4675) SIG_NAME GND\g
J 0
(-2215 4685);
DISPLAY 0.659574 (-2215 4685);
PAINT MONO (-2215 4685);
DISPLAY INVISIBLE (-2215 4685);
FORCEPROP 1 LAST HDL_POWER GND
J 1
(-2200 4550);
DISPLAY 0.489362 (-2200 4550);
PAINT GREEN (-2200 4550);
FORCEPROP 1 LAST PATH I53
J 0
(-2150 4625);
DISPLAY 0.872340 (-2150 4625);
PAINT AQUA (-2150 4625);
DISPLAY INVISIBLE (-2150 4625);
FORCEPROP 2 LAST CDS_LIB pure_quanta_power
J 0
(-2225 4625);
DISPLAY INVISIBLE (-2225 4625);
FORCEPROP 2 LAST BOM_COST MISC.
J 0
(-2200 4600);
DISPLAY 0.680851 (-2200 4600);
DISPLAY INVISIBLE (-2200 4600);
FORCEADD Q_LED..1
(-2700 5150);
FORCEPROP 1 LAST LOCATION D8
J 0
(-2800 5335);
DISPLAY 0.489362 (-2800 5335);
PAINT SKYBLUE (-2800 5335);
FORCEPROP 0 LAST $SEC 1
J 0
(-2800 5375);
DISPLAY 0.680851 (-2800 5375);
PAINT MONO (-2800 5375);
DISPLAY INVISIBLE (-2800 5375);
FORCEPROP 0 LAST CDS_SEC 1
J 0
(-2800 5375);
DISPLAY 0.680851 (-2800 5375);
DISPLAY INVISIBLE (-2800 5375);
FORCEPROP 0 LASTPIN (-2850 5150) $PN A
J 2
(-2860 5160);
DISPLAY 0.489362 (-2860 5160);
PAINT MONO (-2860 5160);
FORCEPROP 0 LASTPIN (-2550 5150) $PN C
J 0
(-2540 5160);
DISPLAY 0.489362 (-2540 5160);
PAINT MONO (-2540 5160);
FORCEPROP 2 LAST PACK_TYPE SMLF
J 0
(-2875 5050);
DISPLAY 0.489362 (-2875 5050);
PAINT SKYBLUE (-2875 5050);
FORCEPROP 2 LAST COLOR LED_RED
J 0
(-2650 5050);
DISPLAY 0.489362 (-2650 5050);
FORCEPROP 1 LAST PART_NUMBER BERD0021Z02
J 0
(-2800 5285);
DISPLAY 0.489362 (-2800 5285);
PAINT SKYBLUE (-2800 5285);
FORCEPROP 1 LAST MATERIAL IC
J 0
(-2800 5230);
DISPLAY 0.489362 (-2800 5230);
PAINT SKYBLUE (-2800 5230);
FORCEPROP 1 LAST PATH I54
J 0
(-2575 5230);
DISPLAY 0.723404 (-2575 5230);
PAINT GREEN (-2575 5230);
DISPLAY INVISIBLE (-2575 5230);
FORCEPROP 0 LAST MANUF_PN LTST-C190KRKT
J 0
(-2875 5000);
DISPLAY 0.680851 (-2875 5000);
DISPLAY INVISIBLE (-2875 5000);
FORCEPROP 2 LAST CDS_LIB pure_quanta
J 0
(-2700 5150);
DISPLAY INVISIBLE (-2700 5150);
FORCEPROP 1 LAST NEEDS_NO_SIZE TRUE
J 0
(-2700 5150);
DISPLAY 0.468085 (-2700 5150);
PAINT GREEN (-2700 5150);
DISPLAY INVISIBLE (-2700 5150);
FORCEADD Q_RES..1
(-3875 5500);
FORCEPROP 1 LAST LOCATION R1194
J 0
(-3950 5575);
DISPLAY 0.489362 (-3950 5575);
PAINT SKYBLUE (-3950 5575);
FORCEPROP 0 LAST $SEC 1
J 0
(-3925 5600);
DISPLAY 0.680851 (-3925 5600);
PAINT MONO (-3925 5600);
DISPLAY INVISIBLE (-3925 5600);
FORCEPROP 0 LAST CDS_SEC 1
J 0
(-3925 5600);
DISPLAY 0.680851 (-3925 5600);
DISPLAY INVISIBLE (-3925 5600);
FORCEPROP 1 LASTPIN (-3975 5500) $PN 1
J 0
(-3963 5512);
DISPLAY 0.489362 (-3963 5512);
PAINT MONO (-3963 5512);
FORCEPROP 1 LASTPIN (-3775 5500) $PN 2
J 0
(-3813 5512);
DISPLAY 0.489362 (-3813 5512);
PAINT MONO (-3813 5512);
FORCEPROP 1 LAST PACK_TYPE 0402LF
J 0
(-3650 5425);
DISPLAY 0.489362 (-3650 5425);
PAINT SKYBLUE (-3650 5425);
FORCEPROP 1 LAST PART_NUMBER CS12002FB06
J 0
(-3500 5425);
DISPLAY 0.489362 (-3500 5425);
PAINT SKYBLUE (-3500 5425);
FORCEPROP 1 LAST VALUE 200
J 2
(-4025 5425);
DISPLAY 0.489362 (-4025 5425);
PAINT SKYBLUE (-4025 5425);
FORCEPROP 1 LAST TOLERANCE 1%
J 0
(-4000 5425);
DISPLAY 0.489362 (-4000 5425);
PAINT SKYBLUE (-4000 5425);
FORCEPROP 1 LAST MATERIAL CHIP
J 0
(-3775 5425);
DISPLAY 0.489362 (-3775 5425);
PAINT SKYBLUE (-3775 5425);
FORCEPROP 1 LAST WATTAGE 1/16W
J 2
(-3800 5425);
DISPLAY 0.489362 (-3800 5425);
PAINT SKYBLUE (-3800 5425);
FORCEPROP 1 LAST PATH I55
J 0
(-3925 5650);
DISPLAY 0.978723 (-3925 5650);
PAINT WHITE (-3925 5650);
DISPLAY INVISIBLE (-3925 5650);
FORCEPROP 2 LAST CDS_LIB pure_quanta
J 0
(-3875 5500);
DISPLAY INVISIBLE (-3875 5500);
FORCEADD OFFPAGE..1
(-3050 4800);
FORCEPROP 2 LAST $XR0 80 
J 0
(-3271 4800);
DISPLAY 0.638298 (-3271 4800);
PAINT MONO (-3271 4800);
FORCEPROP 2 LAST PATH I56
J 0
(-3250 4850);
DISPLAY 0.680851 (-3250 4850);
DISPLAY INVISIBLE (-3250 4850);
FORCEPROP 1 LAST COMMENT_BODY TRUE
J 0
(-2925 4700);
DISPLAY 0.872340 (-2925 4700);
PAINT GREEN (-2925 4700);
DISPLAY INVISIBLE (-2925 4700);
FORCEPROP 1 LAST OFFPAGE TRUE
J 0
(-2725 4675);
DISPLAY 0.872340 (-2725 4675);
PAINT GREEN (-2725 4675);
DISPLAY INVISIBLE (-2725 4675);
FORCEPROP 2 LAST CDS_LIB standard
J 0
(-3050 4800);
DISPLAY INVISIBLE (-3050 4800);
FORCEADD Q_RES..1
(-3875 5150);
FORCEPROP 1 LAST LOCATION R1266
J 0
(-3925 5200);
DISPLAY 0.489362 (-3925 5200);
PAINT SKYBLUE (-3925 5200);
FORCEPROP 0 LAST $SEC 1
J 0
(-3925 5250);
DISPLAY 0.680851 (-3925 5250);
PAINT MONO (-3925 5250);
DISPLAY INVISIBLE (-3925 5250);
FORCEPROP 0 LAST CDS_SEC 1
J 0
(-3925 5250);
DISPLAY 0.680851 (-3925 5250);
DISPLAY INVISIBLE (-3925 5250);
FORCEPROP 1 LASTPIN (-3975 5150) $PN 1
J 0
(-3963 5162);
DISPLAY 0.489362 (-3963 5162);
PAINT MONO (-3963 5162);
FORCEPROP 1 LASTPIN (-3775 5150) $PN 2
J 0
(-3813 5162);
DISPLAY 0.489362 (-3813 5162);
PAINT MONO (-3813 5162);
FORCEPROP 1 LAST PACK_TYPE 0402LF
J 0
(-3650 5075);
DISPLAY 0.489362 (-3650 5075);
PAINT SKYBLUE (-3650 5075);
FORCEPROP 1 LAST PART_NUMBER CS12002FB06
J 0
(-3500 5075);
DISPLAY 0.489362 (-3500 5075);
PAINT SKYBLUE (-3500 5075);
FORCEPROP 1 LAST VALUE 200
J 2
(-4025 5075);
DISPLAY 0.489362 (-4025 5075);
PAINT SKYBLUE (-4025 5075);
FORCEPROP 1 LAST TOLERANCE 1%
J 0
(-4000 5075);
DISPLAY 0.489362 (-4000 5075);
PAINT SKYBLUE (-4000 5075);
FORCEPROP 1 LAST MATERIAL CHIP
J 0
(-3775 5075);
DISPLAY 0.489362 (-3775 5075);
PAINT SKYBLUE (-3775 5075);
FORCEPROP 1 LAST WATTAGE 1/16W
J 2
(-3800 5075);
DISPLAY 0.489362 (-3800 5075);
PAINT SKYBLUE (-3800 5075);
FORCEPROP 1 LAST PATH I57
J 0
(-3925 5300);
DISPLAY 0.978723 (-3925 5300);
PAINT WHITE (-3925 5300);
DISPLAY INVISIBLE (-3925 5300);
FORCEPROP 2 LAST CDS_LIB pure_quanta
J 0
(-3875 5150);
DISPLAY INVISIBLE (-3875 5150);
FORCEADD UNIVERSAL_POWER..1
(-4100 5750);
FORCEPROP 3 LASTPIN (-4100 5700) SIG_NAME P3V3_STBY\g
J 0
(-4090 5710);
DISPLAY 0.659574 (-4090 5710);
PAINT MONO (-4090 5710);
DISPLAY INVISIBLE (-4090 5710);
FORCEPROP 1 LAST HDL_POWER P3V3_STBY
J 1
(-4100 5800);
DISPLAY 0.489362 (-4100 5800);
PAINT GREEN (-4100 5800);
FORCEPROP 1 LAST PATH I58
J 0
(-4050 5775);
DISPLAY 0.872340 (-4050 5775);
PAINT AQUA (-4050 5775);
DISPLAY INVISIBLE (-4050 5775);
FORCEPROP 2 LAST CDS_LIB pure_quanta_power
J 0
(-4100 5750);
DISPLAY INVISIBLE (-4100 5750);
FORCEPROP 2 LAST BOM_COST OCP3.0 
J 0
(-4100 5850);
DISPLAY 0.680851 (-4100 5850);
DISPLAY INVISIBLE (-4100 5850);
FORCEADD OFFPAGE..1
(-8425 1975);
FORCEPROP 2 LASTPIN (-8375 1975) SIG_NAME FM_SMB_RST_E1S_2_N
J 0
(-8385 1985);
DISPLAY 0.446809 (-8385 1985);
FORCEPROP 2 LAST $XR0 81 
J 0
(-8646 1975);
DISPLAY 0.638298 (-8646 1975);
PAINT MONO (-8646 1975);
FORCEPROP 2 LAST CDS_LIB standard
J 0
(-8425 1975);
DISPLAY INVISIBLE (-8425 1975);
FORCEPROP 2 LAST PATH I59
J 0
(-8375 2050);
DISPLAY 0.680851 (-8375 2050);
DISPLAY INVISIBLE (-8375 2050);
FORCEPROP 1 LAST OFFPAGE TRUE
J 0
(-8100 1850);
DISPLAY 0.872340 (-8100 1850);
PAINT GREEN (-8100 1850);
DISPLAY INVISIBLE (-8100 1850);
FORCEPROP 1 LAST COMMENT_BODY TRUE
J 0
(-8300 1875);
DISPLAY 0.872340 (-8300 1875);
PAINT GREEN (-8300 1875);
DISPLAY INVISIBLE (-8300 1875);
FORCEADD Q_RES..1
R 2
(-2625 1875);
FORCEPROP 1 LAST LOCATION R13
J 2
(-2725 1875);
DISPLAY 0.489362 (-2725 1875);
PAINT SKYBLUE (-2725 1875);
FORCEPROP 0 LAST $SEC 1
J 0
(-2725 1925);
DISPLAY 0.680851 (-2725 1925);
PAINT MONO (-2725 1925);
DISPLAY INVISIBLE (-2725 1925);
FORCEPROP 0 LAST CDS_SEC 1
J 0
(-2725 1925);
DISPLAY 1.021277 (-2725 1925);
DISPLAY INVISIBLE (-2725 1925);
FORCEPROP 1 LASTPIN (-2525 1875) $PN 1
J 2
(-2537 1887);
DISPLAY 0.489362 (-2537 1887);
PAINT MONO (-2537 1887);
FORCEPROP 1 LASTPIN (-2725 1875) $PN 2
J 2
(-2687 1887);
DISPLAY 0.489362 (-2687 1887);
PAINT MONO (-2687 1887);
FORCEPROP 1 LAST VALUE 0
J 0
(-2500 1875);
DISPLAY 0.489362 (-2500 1875);
PAINT SKYBLUE (-2500 1875);
FORCEPROP 2 LAST ROOM RST_CPU0_PLD_TO_DIMM
J 0
(-2650 1975);
DISPLAY 0.744681 (-2650 1975);
PAINT RED (-2650 1975);
DISPLAY INVISIBLE (-2650 1975);
FORCEPROP 1 LAST PACK_TYPE 0402LF
J 0
(-2800 1800);
DISPLAY 0.489362 (-2800 1800);
PAINT SKYBLUE (-2800 1800);
DISPLAY INVISIBLE (-2800 1800);
FORCEPROP 1 LAST PART_NUMBER CS00002JB38
J 0
(-2725 1925);
DISPLAY 0.489362 (-2725 1925);
PAINT SKYBLUE (-2725 1925);
DISPLAY INVISIBLE (-2725 1925);
FORCEPROP 1 LAST TOLERANCE 5%
J 2
(-2500 1850);
DISPLAY 0.489362 (-2500 1850);
PAINT SKYBLUE (-2500 1850);
DISPLAY INVISIBLE (-2500 1850);
FORCEPROP 1 LAST MATERIAL CHIP
J 0
(-2800 1850);
DISPLAY 0.489362 (-2800 1850);
PAINT SKYBLUE (-2800 1850);
DISPLAY INVISIBLE (-2800 1850);
FORCEPROP 1 LAST WATTAGE 1/16W
J 0
(-2550 1800);
DISPLAY 0.489362 (-2550 1800);
PAINT SKYBLUE (-2550 1800);
DISPLAY INVISIBLE (-2550 1800);
FORCEPROP 1 LAST PATH I6
J 2
(-2575 2025);
DISPLAY 0.978723 (-2575 2025);
PAINT WHITE (-2575 2025);
DISPLAY INVISIBLE (-2575 2025);
FORCEPROP 2 LAST CDS_LIB pure_quanta
J 0
(-2625 1875);
DISPLAY INVISIBLE (-2625 1875);
FORCEPROP 2 LAST BOM_COST MEM
J 0
(-2650 2025);
DISPLAY 0.744681 (-2650 2025);
PAINT WHITE (-2650 2025);
DISPLAY INVISIBLE (-2650 2025);
FORCEADD OFFPAGE..1
(-8425 1925);
FORCEPROP 2 LASTPIN (-8375 1925) SIG_NAME FM_SMB_RST_E1S_3_N
J 0
(-8385 1935);
DISPLAY 0.446809 (-8385 1935);
FORCEPROP 2 LAST $XR0 81 
J 0
(-8646 1925);
DISPLAY 0.638298 (-8646 1925);
PAINT MONO (-8646 1925);
FORCEPROP 2 LAST CDS_LIB standard
J 0
(-8425 1925);
DISPLAY INVISIBLE (-8425 1925);
FORCEPROP 2 LAST PATH I60
J 0
(-8375 2000);
DISPLAY 0.680851 (-8375 2000);
DISPLAY INVISIBLE (-8375 2000);
FORCEPROP 1 LAST COMMENT_BODY TRUE
J 0
(-8300 1825);
DISPLAY 0.872340 (-8300 1825);
PAINT GREEN (-8300 1825);
DISPLAY INVISIBLE (-8300 1825);
FORCEPROP 1 LAST OFFPAGE TRUE
J 0
(-8100 1800);
DISPLAY 0.872340 (-8100 1800);
PAINT GREEN (-8100 1800);
DISPLAY INVISIBLE (-8100 1800);
FORCEADD OFFPAGE..1
(-8425 1875);
FORCEPROP 2 LASTPIN (-8375 1875) SIG_NAME FM_SMB_RST_E1S_4_N
J 0
(-8385 1885);
DISPLAY 0.446809 (-8385 1885);
FORCEPROP 2 LAST $XR0 81 
J 0
(-8646 1875);
DISPLAY 0.638298 (-8646 1875);
PAINT MONO (-8646 1875);
FORCEPROP 2 LAST CDS_LIB standard
J 0
(-8425 1875);
DISPLAY INVISIBLE (-8425 1875);
FORCEPROP 2 LAST PATH I61
J 0
(-8375 1950);
DISPLAY 0.680851 (-8375 1950);
DISPLAY INVISIBLE (-8375 1950);
FORCEPROP 1 LAST COMMENT_BODY TRUE
J 0
(-8300 1775);
DISPLAY 0.872340 (-8300 1775);
PAINT GREEN (-8300 1775);
DISPLAY INVISIBLE (-8300 1775);
FORCEPROP 1 LAST OFFPAGE TRUE
J 0
(-8100 1750);
DISPLAY 0.872340 (-8100 1750);
PAINT GREEN (-8100 1750);
DISPLAY INVISIBLE (-8100 1750);
FORCEADD Q_RES..1
(-7675 1750);
FORCEPROP 1 LAST LOCATION R5001
J 0
(-7875 1750);
DISPLAY 0.489362 (-7875 1750);
PAINT SKYBLUE (-7875 1750);
FORCEPROP 0 LAST $SEC 1
J 0
(-7475 1775);
DISPLAY 0.680851 (-7475 1775);
PAINT MONO (-7475 1775);
DISPLAY INVISIBLE (-7475 1775);
FORCEPROP 0 LAST CDS_SEC 1
J 0
(-7475 1775);
DISPLAY 0.680851 (-7475 1775);
DISPLAY INVISIBLE (-7475 1775);
FORCEPROP 1 LASTPIN (-7775 1750) $PN 1
J 0
(-7763 1762);
DISPLAY 0.787234 (-7763 1762);
PAINT MONO (-7763 1762);
FORCEPROP 1 LASTPIN (-7575 1750) $PN 2
J 0
(-7613 1762);
DISPLAY 0.787234 (-7613 1762);
PAINT MONO (-7613 1762);
FORCEPROP 1 LAST VALUE 4.7K
J 0
(-7475 1750);
DISPLAY 0.489362 (-7475 1750);
PAINT SKYBLUE (-7475 1750);
FORCEPROP 2 LAST CDS_LIB pure_quanta
J 0
(-7675 1750);
DISPLAY INVISIBLE (-7675 1750);
FORCEPROP 1 LAST PATH I62
J 0
(-7725 1900);
DISPLAY 0.978723 (-7725 1900);
PAINT WHITE (-7725 1900);
DISPLAY INVISIBLE (-7725 1900);
FORCEPROP 1 LAST PACK_TYPE 0402LF
J 0
(-7425 1600);
DISPLAY 0.510638 (-7425 1600);
PAINT SKYBLUE (-7425 1600);
DISPLAY INVISIBLE (-7425 1600);
FORCEPROP 1 LAST PART_NUMBER TMP_QCS24702JB38
J 0
(-7725 1850);
DISPLAY 0.510638 (-7725 1850);
PAINT SKYBLUE (-7725 1850);
DISPLAY INVISIBLE (-7725 1850);
FORCEPROP 1 LAST TOLERANCE 5%
J 0
(-7550 1750);
DISPLAY 0.510638 (-7550 1750);
PAINT SKYBLUE (-7550 1750);
DISPLAY INVISIBLE (-7550 1750);
FORCEPROP 1 LAST MATERIAL CHIP
J 0
(-7575 1725);
DISPLAY 0.489362 (-7575 1725);
PAINT SKYBLUE (-7575 1725);
DISPLAY INVISIBLE (-7575 1725);
FORCEPROP 1 LAST WATTAGE 1/16W
J 2
(-7700 1600);
DISPLAY 0.510638 (-7700 1600);
PAINT SKYBLUE (-7700 1600);
DISPLAY INVISIBLE (-7700 1600);
FORCEADD Q_RES..1
(-7675 1700);
FORCEPROP 1 LAST LOCATION R5002
J 0
(-7875 1700);
DISPLAY 0.489362 (-7875 1700);
PAINT SKYBLUE (-7875 1700);
FORCEPROP 0 LAST $SEC 1
J 0
(-7475 1725);
DISPLAY 0.680851 (-7475 1725);
PAINT MONO (-7475 1725);
DISPLAY INVISIBLE (-7475 1725);
FORCEPROP 0 LAST CDS_SEC 1
J 0
(-7475 1725);
DISPLAY 0.680851 (-7475 1725);
DISPLAY INVISIBLE (-7475 1725);
FORCEPROP 1 LASTPIN (-7775 1700) $PN 1
J 0
(-7763 1712);
DISPLAY 0.787234 (-7763 1712);
PAINT MONO (-7763 1712);
FORCEPROP 1 LASTPIN (-7575 1700) $PN 2
J 0
(-7613 1712);
DISPLAY 0.787234 (-7613 1712);
PAINT MONO (-7613 1712);
FORCEPROP 1 LAST VALUE 4.7K
J 0
(-7475 1700);
DISPLAY 0.489362 (-7475 1700);
PAINT SKYBLUE (-7475 1700);
FORCEPROP 2 LAST CDS_LIB pure_quanta
J 0
(-7675 1700);
DISPLAY INVISIBLE (-7675 1700);
FORCEPROP 1 LAST PATH I63
J 0
(-7725 1850);
DISPLAY 0.978723 (-7725 1850);
PAINT WHITE (-7725 1850);
DISPLAY INVISIBLE (-7725 1850);
FORCEPROP 1 LAST WATTAGE 1/16W
J 2
(-7700 1550);
DISPLAY 0.510638 (-7700 1550);
PAINT SKYBLUE (-7700 1550);
DISPLAY INVISIBLE (-7700 1550);
FORCEPROP 1 LAST MATERIAL CHIP
J 0
(-7575 1675);
DISPLAY 0.489362 (-7575 1675);
PAINT SKYBLUE (-7575 1675);
DISPLAY INVISIBLE (-7575 1675);
FORCEPROP 1 LAST TOLERANCE 5%
J 0
(-7550 1700);
DISPLAY 0.510638 (-7550 1700);
PAINT SKYBLUE (-7550 1700);
DISPLAY INVISIBLE (-7550 1700);
FORCEPROP 1 LAST PART_NUMBER TMP_QCS24702JB38
J 0
(-7725 1800);
DISPLAY 0.510638 (-7725 1800);
PAINT SKYBLUE (-7725 1800);
DISPLAY INVISIBLE (-7725 1800);
FORCEPROP 1 LAST PACK_TYPE 0402LF
J 0
(-7425 1550);
DISPLAY 0.510638 (-7425 1550);
PAINT SKYBLUE (-7425 1550);
DISPLAY INVISIBLE (-7425 1550);
FORCEADD Q_RES..1
(-7675 1650);
FORCEPROP 1 LAST LOCATION R5003
J 0
(-7875 1650);
DISPLAY 0.489362 (-7875 1650);
PAINT SKYBLUE (-7875 1650);
FORCEPROP 0 LAST $SEC 1
J 0
(-7475 1675);
DISPLAY 0.680851 (-7475 1675);
PAINT MONO (-7475 1675);
DISPLAY INVISIBLE (-7475 1675);
FORCEPROP 0 LAST CDS_SEC 1
J 0
(-7475 1675);
DISPLAY 0.680851 (-7475 1675);
DISPLAY INVISIBLE (-7475 1675);
FORCEPROP 1 LASTPIN (-7775 1650) $PN 1
J 0
(-7763 1662);
DISPLAY 0.787234 (-7763 1662);
PAINT MONO (-7763 1662);
FORCEPROP 1 LASTPIN (-7575 1650) $PN 2
J 0
(-7613 1662);
DISPLAY 0.787234 (-7613 1662);
PAINT MONO (-7613 1662);
FORCEPROP 1 LAST VALUE 4.7K
J 0
(-7475 1650);
DISPLAY 0.489362 (-7475 1650);
PAINT SKYBLUE (-7475 1650);
FORCEPROP 2 LAST CDS_LIB pure_quanta
J 0
(-7675 1650);
DISPLAY INVISIBLE (-7675 1650);
FORCEPROP 1 LAST PATH I64
J 0
(-7725 1800);
DISPLAY 0.978723 (-7725 1800);
PAINT WHITE (-7725 1800);
DISPLAY INVISIBLE (-7725 1800);
FORCEPROP 1 LAST WATTAGE 1/16W
J 2
(-7700 1500);
DISPLAY 0.510638 (-7700 1500);
PAINT SKYBLUE (-7700 1500);
DISPLAY INVISIBLE (-7700 1500);
FORCEPROP 1 LAST MATERIAL CHIP
J 0
(-7575 1625);
DISPLAY 0.489362 (-7575 1625);
PAINT SKYBLUE (-7575 1625);
DISPLAY INVISIBLE (-7575 1625);
FORCEPROP 1 LAST TOLERANCE 5%
J 0
(-7550 1650);
DISPLAY 0.510638 (-7550 1650);
PAINT SKYBLUE (-7550 1650);
DISPLAY INVISIBLE (-7550 1650);
FORCEPROP 1 LAST PART_NUMBER TMP_QCS24702JB38
J 0
(-7725 1750);
DISPLAY 0.510638 (-7725 1750);
PAINT SKYBLUE (-7725 1750);
DISPLAY INVISIBLE (-7725 1750);
FORCEPROP 1 LAST PACK_TYPE 0402LF
J 0
(-7425 1500);
DISPLAY 0.510638 (-7425 1500);
PAINT SKYBLUE (-7425 1500);
DISPLAY INVISIBLE (-7425 1500);
FORCEADD Q_RES..1
R 2
(-2625 1925);
FORCEPROP 1 LAST LOCATION R9
J 2
(-2725 1925);
DISPLAY 0.489362 (-2725 1925);
PAINT SKYBLUE (-2725 1925);
FORCEPROP 0 LAST $SEC 1
J 0
(-2725 1975);
DISPLAY 0.680851 (-2725 1975);
PAINT MONO (-2725 1975);
DISPLAY INVISIBLE (-2725 1975);
FORCEPROP 0 LAST CDS_SEC 1
J 0
(-2725 1975);
DISPLAY 1.021277 (-2725 1975);
DISPLAY INVISIBLE (-2725 1975);
FORCEPROP 1 LASTPIN (-2525 1925) $PN 1
J 2
(-2537 1937);
DISPLAY 0.489362 (-2537 1937);
PAINT MONO (-2537 1937);
FORCEPROP 1 LASTPIN (-2725 1925) $PN 2
J 2
(-2687 1937);
DISPLAY 0.489362 (-2687 1937);
PAINT MONO (-2687 1937);
FORCEPROP 1 LAST VALUE 0
J 0
(-2500 1925);
DISPLAY 0.489362 (-2500 1925);
PAINT SKYBLUE (-2500 1925);
FORCEPROP 2 LAST ROOM RST_CPU0_PLD_TO_DIMM
J 0
(-2650 2025);
DISPLAY 0.744681 (-2650 2025);
PAINT RED (-2650 2025);
DISPLAY INVISIBLE (-2650 2025);
FORCEPROP 1 LAST PACK_TYPE 0402LF
J 0
(-2800 1850);
DISPLAY 0.489362 (-2800 1850);
PAINT SKYBLUE (-2800 1850);
DISPLAY INVISIBLE (-2800 1850);
FORCEPROP 1 LAST PART_NUMBER CS00002JB38
J 0
(-2725 1975);
DISPLAY 0.489362 (-2725 1975);
PAINT SKYBLUE (-2725 1975);
DISPLAY INVISIBLE (-2725 1975);
FORCEPROP 1 LAST TOLERANCE 5%
J 2
(-2500 1900);
DISPLAY 0.489362 (-2500 1900);
PAINT SKYBLUE (-2500 1900);
DISPLAY INVISIBLE (-2500 1900);
FORCEPROP 1 LAST MATERIAL CHIP
J 0
(-2800 1900);
DISPLAY 0.489362 (-2800 1900);
PAINT SKYBLUE (-2800 1900);
DISPLAY INVISIBLE (-2800 1900);
FORCEPROP 1 LAST WATTAGE 1/16W
J 0
(-2550 1850);
DISPLAY 0.489362 (-2550 1850);
PAINT SKYBLUE (-2550 1850);
DISPLAY INVISIBLE (-2550 1850);
FORCEPROP 1 LAST PATH I7
J 2
(-2575 2075);
DISPLAY 0.978723 (-2575 2075);
PAINT WHITE (-2575 2075);
DISPLAY INVISIBLE (-2575 2075);
FORCEPROP 2 LAST CDS_LIB pure_quanta
J 0
(-2625 1925);
DISPLAY INVISIBLE (-2625 1925);
FORCEPROP 2 LAST BOM_COST MEM
J 0
(-2650 2075);
DISPLAY 0.744681 (-2650 2075);
PAINT WHITE (-2650 2075);
DISPLAY INVISIBLE (-2650 2075);
FORCEADD Q_RES..1
R 2
(-2625 1725);
FORCEPROP 1 LAST LOCATION R14
J 2
(-2725 1725);
DISPLAY 0.489362 (-2725 1725);
PAINT SKYBLUE (-2725 1725);
FORCEPROP 0 LAST $SEC 1
J 0
(-2725 1775);
DISPLAY 0.680851 (-2725 1775);
PAINT MONO (-2725 1775);
DISPLAY INVISIBLE (-2725 1775);
FORCEPROP 0 LAST CDS_SEC 1
J 0
(-2725 1775);
DISPLAY 1.021277 (-2725 1775);
DISPLAY INVISIBLE (-2725 1775);
FORCEPROP 1 LASTPIN (-2525 1725) $PN 1
J 2
(-2537 1737);
DISPLAY 0.489362 (-2537 1737);
PAINT MONO (-2537 1737);
FORCEPROP 1 LASTPIN (-2725 1725) $PN 2
J 2
(-2687 1737);
DISPLAY 0.489362 (-2687 1737);
PAINT MONO (-2687 1737);
FORCEPROP 1 LAST VALUE 0
J 0
(-2500 1725);
DISPLAY 0.489362 (-2500 1725);
PAINT SKYBLUE (-2500 1725);
FORCEPROP 2 LAST ROOM RST_CPU0_PLD_TO_DIMM
J 0
(-2650 1825);
DISPLAY 0.744681 (-2650 1825);
PAINT RED (-2650 1825);
DISPLAY INVISIBLE (-2650 1825);
FORCEPROP 1 LAST PACK_TYPE 0402LF
J 0
(-2800 1650);
DISPLAY 0.489362 (-2800 1650);
PAINT SKYBLUE (-2800 1650);
DISPLAY INVISIBLE (-2800 1650);
FORCEPROP 1 LAST PART_NUMBER CS00002JB38
J 0
(-2725 1775);
DISPLAY 0.489362 (-2725 1775);
PAINT SKYBLUE (-2725 1775);
DISPLAY INVISIBLE (-2725 1775);
FORCEPROP 1 LAST TOLERANCE 5%
J 2
(-2500 1700);
DISPLAY 0.489362 (-2500 1700);
PAINT SKYBLUE (-2500 1700);
DISPLAY INVISIBLE (-2500 1700);
FORCEPROP 1 LAST MATERIAL CHIP
J 0
(-2800 1700);
DISPLAY 0.489362 (-2800 1700);
PAINT SKYBLUE (-2800 1700);
DISPLAY INVISIBLE (-2800 1700);
FORCEPROP 1 LAST WATTAGE 1/16W
J 0
(-2550 1650);
DISPLAY 0.489362 (-2550 1650);
PAINT SKYBLUE (-2550 1650);
DISPLAY INVISIBLE (-2550 1650);
FORCEPROP 1 LAST PATH I8
J 2
(-2575 1875);
DISPLAY 0.978723 (-2575 1875);
PAINT WHITE (-2575 1875);
DISPLAY INVISIBLE (-2575 1875);
FORCEPROP 2 LAST CDS_LIB pure_quanta
J 0
(-2625 1725);
DISPLAY INVISIBLE (-2625 1725);
FORCEPROP 2 LAST BOM_COST MEM
J 0
(-2650 1875);
DISPLAY 0.744681 (-2650 1875);
PAINT WHITE (-2650 1875);
DISPLAY INVISIBLE (-2650 1875);
FORCEADD Q_RES..1
R 2
(-2625 1625);
FORCEPROP 1 LAST LOCATION R15
J 2
(-2725 1625);
DISPLAY 0.489362 (-2725 1625);
PAINT SKYBLUE (-2725 1625);
FORCEPROP 0 LAST $SEC 1
J 0
(-2725 1675);
DISPLAY 0.680851 (-2725 1675);
PAINT MONO (-2725 1675);
DISPLAY INVISIBLE (-2725 1675);
FORCEPROP 0 LAST CDS_SEC 1
J 0
(-2725 1675);
DISPLAY 1.021277 (-2725 1675);
DISPLAY INVISIBLE (-2725 1675);
FORCEPROP 1 LASTPIN (-2525 1625) $PN 1
J 2
(-2537 1637);
DISPLAY 0.489362 (-2537 1637);
PAINT MONO (-2537 1637);
FORCEPROP 1 LASTPIN (-2725 1625) $PN 2
J 2
(-2687 1637);
DISPLAY 0.489362 (-2687 1637);
PAINT MONO (-2687 1637);
FORCEPROP 1 LAST VALUE 0
J 0
(-2500 1625);
DISPLAY 0.489362 (-2500 1625);
PAINT SKYBLUE (-2500 1625);
FORCEPROP 2 LAST ROOM RST_CPU0_PLD_TO_DIMM
J 0
(-2650 1725);
DISPLAY 0.744681 (-2650 1725);
PAINT RED (-2650 1725);
DISPLAY INVISIBLE (-2650 1725);
FORCEPROP 1 LAST PACK_TYPE 0402LF
J 0
(-2800 1550);
DISPLAY 0.489362 (-2800 1550);
PAINT SKYBLUE (-2800 1550);
DISPLAY INVISIBLE (-2800 1550);
FORCEPROP 1 LAST PART_NUMBER CS00002JB38
J 0
(-2725 1675);
DISPLAY 0.489362 (-2725 1675);
PAINT SKYBLUE (-2725 1675);
DISPLAY INVISIBLE (-2725 1675);
FORCEPROP 1 LAST TOLERANCE 5%
J 2
(-2500 1600);
DISPLAY 0.489362 (-2500 1600);
PAINT SKYBLUE (-2500 1600);
DISPLAY INVISIBLE (-2500 1600);
FORCEPROP 1 LAST MATERIAL CHIP
J 0
(-2800 1600);
DISPLAY 0.489362 (-2800 1600);
PAINT SKYBLUE (-2800 1600);
DISPLAY INVISIBLE (-2800 1600);
FORCEPROP 1 LAST WATTAGE 1/16W
J 0
(-2550 1550);
DISPLAY 0.489362 (-2550 1550);
PAINT SKYBLUE (-2550 1550);
DISPLAY INVISIBLE (-2550 1550);
FORCEPROP 1 LAST PATH I9
J 2
(-2575 1775);
DISPLAY 0.978723 (-2575 1775);
PAINT WHITE (-2575 1775);
DISPLAY INVISIBLE (-2575 1775);
FORCEPROP 2 LAST BOM_COST MEM
J 0
(-2650 1775);
DISPLAY 0.744681 (-2650 1775);
PAINT WHITE (-2650 1775);
DISPLAY INVISIBLE (-2650 1775);
FORCEPROP 2 LAST CDS_LIB pure_quanta
J 0
(-2625 1625);
DISPLAY INVISIBLE (-2625 1625);
FORCEADD CAD_NOTE..1
(-8325 5000);
FORCEPROP 0 LAST L1 R242 R203 R1422 C0-LAY
J 0
(-8475 4875);
DISPLAY 0.617021 (-8475 4875);
PAINT WHITE (-8475 4875);
FORCEPROP 1 LAST COMMENT_BODY TRUE
J 0
(-8300 5100);
DISPLAY 0.574468 (-8300 5100);
PAINT WHITE (-8300 5100);
DISPLAY INVISIBLE (-8300 5100);
FORCEPROP 2 LAST CDS_LIB pure_quanta_power
J 0
(-8325 5000);
DISPLAY INVISIBLE (-8325 5000);
FORCEADD CAD_NOTE..1
(-6575 4925);
FORCEPROP 0 LAST L1 R241 R57 R530 CO-LAY
J 0
(-6725 4800);
DISPLAY 0.617021 (-6725 4800);
PAINT WHITE (-6725 4800);
FORCEPROP 1 LAST COMMENT_BODY TRUE
J 0
(-6550 5025);
DISPLAY 0.574468 (-6550 5025);
PAINT WHITE (-6550 5025);
DISPLAY INVISIBLE (-6550 5025);
FORCEPROP 2 LAST CDS_LIB pure_quanta_power
J 0
(-6575 4925);
DISPLAY INVISIBLE (-6575 4925);
FORCEADD QUANTA_TITLE_BLOCK_C..1
(0 0);
FORCEPROP 0 LAST CDS_CON_LAST_MODIFIED Fri Mar 11 14:53:21 2022
J 0
(-1885 15);
DISPLAY INVISIBLE (-1885 15);
FORCEPROP 1 LAST CUSTOM_TXT_CDS <CON_LAST_MODIFIED>
J 0
(-1885 15);
DISPLAY 0.978723 (-1885 15);
FORCEPROP 2 LAST CUSTOM_TXT_CDS <XR_PAGE_TITLE>
J 0
(-7890 5250);
DISPLAY 0.638298 (-7890 5250);
PAINT PINK (-7890 5250);
DISPLAY INVISIBLE (-7890 5250);
FORCEPROP 1 LAST CUSTOM_TXT_CDS <NAME_2>
J 0
(-3175 50);
FORCEPROP 1 LAST CUSTOM_TXT_CDS <NAME_1>
J 0
(-3175 175);
FORCEPROP 1 LAST CUSTOM_TXT_CDS <Q_NUMBER>
J 0
(-1403 103);
DISPLAY 1.212766 (-1403 103);
FORCEPROP 1 LAST CUSTOM_TXT_CDS <Q_PROJ>
J 0
(-2382 102);
DISPLAY 1.212766 (-2382 102);
FORCEPROP 1 LAST CUSTOM_TXT_CDS <Q_REV>
J 0
(-184 103);
DISPLAY 1.212766 (-184 103);
FORCEPROP 1 LAST CUSTOM_TXT_CDS <CON_PAGE_NUM> OF <CON_TOTAL_PAGES>
J 0
(-446 18);
DISPLAY 0.978723 (-446 18);
FORCEPROP 1 LAST Q_TITLE FPGA 6/6
J 0
(-9275 75);
DISPLAY 2.446809 (-9275 75);
PAINT GREEN (-9275 75);
FORCEPROP 1 LAST Q_DEPT BU9
J 1
(-3763 49);
DISPLAY 1.957447 (-3763 49);
PAINT GREEN (-3763 49);
FORCEPROP 1 LAST COMMENT_BODY TRUE
J 0
(12 -13);
DISPLAY 0.978723 (12 -13);
PAINT GREEN (12 -13);
DISPLAY INVISIBLE (12 -13);
FORCEPROP 2 LAST CDS_LIB pure_quanta
J 0
(0 0);
DISPLAY INVISIBLE (0 0);
FORCEPROP 1 LAST CDS_LMAN_SYM_OUTLINE -9475,6775,100,-125
J 0
(0 0);
DISPLAY 0.468085 (0 0);
PAINT GREEN (0 0);
DISPLAY INVISIBLE (0 0);
FORCEPROP 2 LAST PAGE_BORDER TRUE
J 0
(-7890 5250);
DISPLAY 0.638298 (-7890 5250);
PAINT PINK (-7890 5250);
DISPLAY INVISIBLE (-7890 5250);
FORCEPROP 2 LAST CDS_XR_PAGE_TITLE CR-84 : @T6G_MB_LIB.T6G(SCH_1):PAGE84
J 0
(-7890 5250);
DISPLAY 0.638298 (-7890 5250);
PAINT PINK (-7890 5250);
DISPLAY INVISIBLE (-7890 5250);
WIRE 16 -1 (-1725 1675)(-1800 1675);
WIRE 16 -1 (-1800 1675)(-1800 1550);
WIRE 16 -1 (-1450 4750)(-1450 4675);
WIRE 16 -1 (-1550 4750)(-1450 4750);
WIRE 16 -1 (-2150 4750)(-2225 4750);
WIRE 16 -1 (-2225 4750)(-2225 4675);
WIRE 16 -1 (-8450 5175)(-7625 5175);
FORCEPROP 2 LAST SIG_NAME PWRGD_CPU1_PWROK
J 0
(-8360 5185);
DISPLAY 0.489362 (-8360 5185);
WIRE 16 -1 (-7850 2500)(-7675 2500);
WIRE 16 -1 (-7850 2550)(-7850 2500);
WIRE 16 -1 (-7850 2550)(-7675 2550);
WIRE 16 -1 (-7850 2600)(-7850 2550);
WIRE 16 -1 (-7850 2600)(-7675 2600);
WIRE 16 -1 (-7850 2650)(-7850 2600);
WIRE 16 -1 (-7850 2650)(-7675 2650);
WIRE 16 -1 (-8400 2650)(-7850 2650);
FORCEPROP 2 LAST SIG_NAME RST_PERST_OCP_SFF_N
J 0
(-8335 2660);
DISPLAY 0.489362 (-8335 2660);
WIRE 16 -1 (-7900 1800)(-7775 1800);
WIRE 16 -1 (-7900 1800)(-7900 2025);
WIRE 16 -1 (-7900 2025)(-7775 2025);
WIRE 16 -1 (-8375 2025)(-7900 2025);
WIRE 16 -1 (-3975 5150)(-4100 5150);
WIRE 16 -1 (-4100 5500)(-4100 5150);
WIRE 16 -1 (-4100 5700)(-4100 5500);
WIRE 16 -1 (-3975 5500)(-4100 5500);
WIRE 16 -1 (-7575 1650)(-7350 1650);
WIRE 16 -1 (-7350 1650)(-7350 1700);
WIRE 16 -1 (-7575 1700)(-7350 1700);
WIRE 16 -1 (-7350 1700)(-7350 1750);
WIRE 16 -1 (-7350 1750)(-7350 1800);
WIRE 16 -1 (-7575 1750)(-7350 1750);
WIRE 16 -1 (-7350 1800)(-7300 1800);
WIRE 16 -1 (-7575 1800)(-7350 1800);
WIRE 16 -1 (-1775 1975)(-1775 2350);
WIRE 16 -1 (-1775 1975)(-1725 1975);
WIRE 16 -1 (-1775 2350)(-1775 2425);
WIRE 16 -1 (-1900 2350)(-1775 2350);
WIRE 16 -1 (-1900 2275)(-1900 2350);
WIRE 16 -1 (-7950 1750)(-7775 1750);
WIRE 16 -1 (-7950 1975)(-7950 1750);
WIRE 16 -1 (-7775 1975)(-7950 1975);
WIRE 16 -1 (-7950 1975)(-8375 1975);
WIRE 16 -1 (-8050 1650)(-7775 1650);
WIRE 16 -1 (-8050 1875)(-8050 1650);
WIRE 16 -1 (-7775 1875)(-8050 1875);
WIRE 16 -1 (-8050 1875)(-8375 1875);
WIRE 16 -1 (-8000 1700)(-7775 1700);
WIRE 16 -1 (-8000 1925)(-8000 1700);
WIRE 16 -1 (-7775 1925)(-8000 1925);
WIRE 16 -1 (-8000 1925)(-8375 1925);
WIRE 16 -1 (-8450 5375)(-7625 5375);
FORCEPROP 2 LAST SIG_NAME PWRGD_CPU0_PWROK
J 0
(-8360 5385);
DISPLAY 0.489362 (-8360 5385);
WIRE 16 -1 (-6350 2025)(-7575 2025);
FORCEPROP 0 LAST SIG_NAME FM_SMB_RST_E1S_1_N_R
J 0
(-6785 2035);
DISPLAY 0.489362 (-6785 2035);
WIRE 16 -1 (-6350 1975)(-7575 1975);
FORCEPROP 0 LAST SIG_NAME FM_SMB_RST_E1S_2_N_R
J 0
(-6785 1985);
DISPLAY 0.489362 (-6785 1985);
WIRE 16 -1 (-6350 1925)(-7575 1925);
FORCEPROP 0 LAST SIG_NAME FM_SMB_RST_E1S_3_N_R
J 0
(-6785 1935);
DISPLAY 0.489362 (-6785 1935);
WIRE 16 -1 (-6350 1875)(-7575 1875);
FORCEPROP 0 LAST SIG_NAME FM_SMB_RST_E1S_4_N_R
J 0
(-6785 1885);
DISPLAY 0.489362 (-6785 1885);
WIRE 16 -1 (-7475 2600)(-6850 2600);
FORCEPROP 2 LAST SIG_NAME RST_PERST1_OCP_SFF_N
J 0
(-7310 2610);
DISPLAY 0.489362 (-7310 2610);
WIRE 16 -1 (-7475 2650)(-6850 2650);
FORCEPROP 2 LAST SIG_NAME RST_PERST0_OCP_SFF_N
J 0
(-7310 2660);
DISPLAY 0.489362 (-7310 2660);
WIRE 16 -1 (-7475 2550)(-6850 2550);
FORCEPROP 2 LAST SIG_NAME RST_PERST2_OCP_SFF_N
J 0
(-7310 2560);
DISPLAY 0.489362 (-7310 2560);
WIRE 16 -1 (-7475 2500)(-6850 2500);
FORCEPROP 2 LAST SIG_NAME RST_PERST3_OCP_SFF_N
J 0
(-7310 2510);
DISPLAY 0.489362 (-7310 2510);
WIRE 16 -1 (-6725 5175)(-5950 5175);
FORCEPROP 2 LAST SIG_NAME RST_CPU1_RESETL_N
J 0
(-6500 5185);
DISPLAY 0.489362 (-6500 5185);
WIRE 16 -1 (-6725 5375)(-5950 5375);
FORCEPROP 2 LAST SIG_NAME RST_CPU0_RESETL_N
J 0
(-6500 5385);
DISPLAY 0.489362 (-6500 5385);
WIRE 16 -1 (-3475 1875)(-2725 1875);
FORCEPROP 2 LAST SIG_NAME JTAG_SCM_PLD_TDO
J 0
(-3475 1885);
DISPLAY 0.489362 (-3475 1885);
WIRE 16 -1 (-3475 1925)(-2725 1925);
FORCEPROP 2 LAST SIG_NAME JTAG_SCM_PLD_TDI
J 0
(-3475 1935);
DISPLAY 0.489362 (-3475 1935);
WIRE 16 -1 (-3500 1725)(-2725 1725);
FORCEPROP 2 LAST SIG_NAME JTAG_SCM_PLD_TMS
J 0
(-3460 1750);
DISPLAY 0.489362 (-3460 1750);
WIRE 16 -1 (-3500 1625)(-2725 1625);
FORCEPROP 2 LAST SIG_NAME JTAG_SCM_PLD_TCK
J 0
(-3460 1650);
DISPLAY 0.489362 (-3460 1650);
WIRE 16 -1 (-2525 1875)(-1725 1875);
FORCEPROP 2 LAST SIG_NAME JTAG_PLD_TDO
J 0
(-2235 1885);
DISPLAY 0.489362 (-2235 1885);
FORCEPROP 2 LASTPROP $XRERR UNIQUE?
J 0
(-2475 1885);
DISPLAY 0.638298 (-2475 1885);
PAINT MONO (-2475 1885);
DISPLAY INVISIBLE (-2475 1885);
WIRE 16 -1 (-2525 1625)(-1725 1625);
FORCEPROP 2 LAST SIG_NAME JTAG_PLD_TCK
J 0
(-2235 1635);
DISPLAY 0.489362 (-2235 1635);
FORCEPROP 2 LASTPROP $XRERR UNIQUE?
J 0
(-2475 1635);
DISPLAY 0.638298 (-2475 1635);
PAINT MONO (-2475 1635);
DISPLAY INVISIBLE (-2475 1635);
WIRE 16 -1 (-2525 1725)(-1725 1725);
FORCEPROP 2 LAST SIG_NAME JTAG_PLD_TMS
J 0
(-2235 1735);
DISPLAY 0.489362 (-2235 1735);
FORCEPROP 2 LASTPROP $XRERR UNIQUE?
J 0
(-2475 1735);
DISPLAY 0.638298 (-2475 1735);
PAINT MONO (-2475 1735);
DISPLAY INVISIBLE (-2475 1735);
WIRE 16 -1 (-2525 1925)(-1725 1925);
FORCEPROP 2 LAST SIG_NAME JTAG_PLD_TDI
J 0
(-2235 1935);
DISPLAY 0.489362 (-2235 1935);
FORCEPROP 2 LASTPROP $XRERR UNIQUE?
J 0
(-2475 1935);
DISPLAY 0.638298 (-2475 1935);
PAINT MONO (-2475 1935);
DISPLAY INVISIBLE (-2475 1935);
WIRE 16 -1 (-2850 5150)(-3775 5150);
FORCEPROP 2 LAST SIG_NAME BMC_HPM_FPGA_LED1_R_N
J 0
(-3710 5160);
DISPLAY 0.489362 (-3710 5160);
FORCEPROP 2 LASTPROP $XRERR UNIQUE?
J 0
(-3950 5160);
DISPLAY 0.638298 (-3950 5160);
PAINT MONO (-3950 5160);
DISPLAY INVISIBLE (-3950 5160);
WIRE 16 -1 (-2875 5500)(-3775 5500);
FORCEPROP 2 LAST SIG_NAME BMC_HPM_FPGA_LED2_R_N
J 0
(-3710 5510);
DISPLAY 0.489362 (-3710 5510);
FORCEPROP 2 LASTPROP $XRERR UNIQUE?
J 0
(-3950 5510);
DISPLAY 0.638298 (-3950 5510);
PAINT MONO (-3950 5510);
DISPLAY INVISIBLE (-3950 5510);
WIRE 16 -1 (-2150 4800)(-3000 4800);
FORCEPROP 2 LAST SIG_NAME BMC_HPM_FPGA_LED1
J 0
(-2835 4810);
DISPLAY 0.489362 (-2835 4810);
WIRE 16 -1 (-2400 5150)(-2400 4850);
WIRE 16 -1 (-2400 5150)(-2550 5150);
FORCEPROP 2 LAST SIG_NAME BMC_HPM_FPGA_LED1_N
J 0
(-2460 5160);
DISPLAY 0.489362 (-2460 5160);
FORCEPROP 2 LASTPROP $XRERR UNIQUE?
J 0
(-2700 5160);
DISPLAY 0.638298 (-2700 5160);
PAINT MONO (-2700 5160);
DISPLAY INVISIBLE (-2700 5160);
WIRE 16 -1 (-2400 4850)(-2150 4850);
WIRE 16 -1 (-1500 5500)(-1500 4850);
WIRE 16 -1 (-2575 5500)(-1500 5500);
FORCEPROP 2 LAST SIG_NAME BMC_HPM_FPGA_LED2_N
J 0
(-2485 5510);
DISPLAY 0.489362 (-2485 5510);
FORCEPROP 2 LASTPROP $XRERR UNIQUE?
J 0
(-2725 5510);
DISPLAY 0.638298 (-2725 5510);
PAINT MONO (-2725 5510);
DISPLAY INVISIBLE (-2725 5510);
WIRE 16 -1 (-1500 4850)(-1550 4850);
WIRE 16 -1 (-875 4800)(-1550 4800);
FORCEPROP 2 LAST SIG_NAME BMC_HPM_FPGA_LED2
J 0
(-1385 4810);
DISPLAY 0.489362 (-1385 4810);
DOT 1 (-7950 1975);
DOT 1 (-7850 2550);
DOT 1 (-7850 2600);
DOT 1 (-7850 2650);
DOT 1 (-1775 2350);
DOT 1 (-4100 5500);
DOT 1 (-7900 2025);
DOT 1 (-8000 1925);
DOT 1 (-8050 1875);
DOT 1 (-7350 1800);
DOT 1 (-7350 1750);
DOT 1 (-7350 1700);
FORCENOTE
CAD NOTE: IF DEPOP R530, PLEASE POP R556
(-7125 4625) 0;
DISPLAY LEFT (-7125 4625);
DISPLAY 1.021277 (-7125 4625);
FORCENOTE
CAD NOTE: IF DEPOP R1422, PLEASE POP R557
(-9000 4750) 0;
DISPLAY LEFT (-9000 4750);
DISPLAY 1.021277 (-9000 4750);
FORCENOTE
PIN2: PROGRAMMER TDI
(-1425 1925) 0;
DISPLAY LEFT (-1425 1925);
DISPLAY 1.021277 (-1425 1925);
FORCENOTE
PIN3: PROGRAMMER TDO
(-1425 1850) 0;
DISPLAY LEFT (-1425 1850);
DISPLAY 1.021277 (-1425 1850);
QUIT
